G04 ================== begin FILE IDENTIFICATION RECORD ==================*
G04 Layout Name:  12004-1.brd*
G04 Film Name:    L5VCC*
G04 File Format:  Gerber RS274X*
G04 File Origin:  Cadence Allegro 16.2-S033*
G04 Origin Date:  Tue Oct 16 14:36:07 2012*
G04 *
G04 Layer:  VIA CLASS/L5VCC*
G04 Layer:  PIN/L5VCC*
G04 Layer:  PACKAGE GEOMETRY/PWRVCC*
G04 Layer:  ETCH/L5VCC*
G04 Layer:  DRAWING FORMAT/LAYER_PCB_STORY*
G04 Layer:  DRAWING FORMAT/LAYER_L5VCC*
G04 *
G04 Offset:    (0.00 0.00)*
G04 Mirror:    No*
G04 Mode:      Negative*
G04 Rotation:  0*
G04 FullContactRelief:  No*
G04 UndefLineWidth:     6.00*
G04 ================== end FILE IDENTIFICATION RECORD ====================*
%FSLAX35Y35*MOIN*%
%IR0*IPPOS*OFA0.00000B0.00000*MIA0B0*SFA1.00000B1.00000*%
%ADD15C,.03*%
%ADD14C,.032*%
%ADD22C,.09*%
%ADD20C,.036*%
%ADD17C,.063*%
%ADD28C,.073*%
%ADD21C,.067*%
%ADD24C,.089*%
%AMMACRO16*
4,1,13,.02327,.00913,
.024502,.004951,
.024989,.000621,
.024717,-.003728,
.023695,-.007964,
.02327,-.00913,
.02707,-.01293,
.028904,-.008033,
.02986,-.002892,
.029908,.002337,
.029048,.007495,
.027305,.012426,
.02707,.01293,
.02327,.00913,
270.*
4,1,13,.00913,-.02327,
.004951,-.024502,
.000621,-.024989,
-.003728,-.024717,
-.007964,-.023695,
-.00913,-.02327,
-.01293,-.02707,
-.008033,-.028904,
-.002892,-.02986,
.002337,-.029908,
.007495,-.029048,
.012426,-.027305,
.01293,-.02707,
.00913,-.02327,
270.*
4,1,13,-.02327,-.00913,
-.024502,-.004951,
-.024989,-.000621,
-.024717,.003728,
-.023695,.007964,
-.02327,.00913,
-.02707,.01293,
-.028904,.008033,
-.02986,.002892,
-.029908,-.002337,
-.029048,-.007495,
-.027305,-.012426,
-.02707,-.01293,
-.02327,-.00913,
270.*
4,1,13,-.00913,.02327,
-.004951,.024502,
-.000621,.024989,
.003728,.024717,
.007964,.023695,
.00913,.02327,
.01293,.02707,
.008033,.028904,
.002892,.02986,
-.002337,.029908,
-.007495,.029048,
-.012426,.027305,
-.01293,.02707,
-.00913,.02327,
270.*
%
%ADD16MACRO16*%
%AMMACRO26*
4,1,15,.00398,.00044,
.003999,.000208,
.004004,-.000025,
.003996,-.000258,
.00398,-.00044,
.00483,-.00129,
.004897,-.001007,
.004947,-.000721,
.004981,-.000432,
.004997,-.000141,
.004997,.000149,
.00498,.00044,
.004946,.000729,
.004895,.001015,
.00483,.00129,
.00398,.00044,
90.*
4,1,15,.00044,-.00398,
.000208,-.003999,
-.000025,-.004004,
-.000258,-.003996,
-.00044,-.00398,
-.00129,-.00483,
-.001007,-.004897,
-.000721,-.004947,
-.000432,-.004981,
-.000141,-.004997,
.000149,-.004997,
.00044,-.00498,
.000729,-.004946,
.001015,-.004895,
.00129,-.00483,
.00044,-.00398,
90.*
4,1,15,-.00398,-.00044,
-.003999,-.000208,
-.004004,.000025,
-.003996,.000258,
-.00398,.00044,
-.00483,.00129,
-.004897,.001007,
-.004947,.000721,
-.004981,.000432,
-.004997,.000141,
-.004997,-.000149,
-.00498,-.00044,
-.004946,-.000729,
-.004895,-.001015,
-.00483,-.00129,
-.00398,-.00044,
90.*
4,1,15,-.00044,.00398,
-.000208,.003999,
.000025,.004004,
.000258,.003996,
.00044,.00398,
.00129,.00483,
.001007,.004897,
.000721,.004947,
.000432,.004981,
.000141,.004997,
-.000149,.004997,
-.00044,.00498,
-.000729,.004946,
-.001015,.004895,
-.00129,.00483,
-.00044,.00398,
90.*
%
%ADD26MACRO26*%
%AMMACRO11*
4,1,15,.00398,.00044,
.003999,.000208,
.004004,-.000025,
.003996,-.000258,
.00398,-.00044,
.00483,-.00129,
.004897,-.001007,
.004947,-.000721,
.004981,-.000432,
.004997,-.000141,
.004997,.000149,
.00498,.00044,
.004946,.000729,
.004895,.001015,
.00483,.00129,
.00398,.00044,
0.0*
4,1,15,.00044,-.00398,
.000208,-.003999,
-.000025,-.004004,
-.000258,-.003996,
-.00044,-.00398,
-.00129,-.00483,
-.001007,-.004897,
-.000721,-.004947,
-.000432,-.004981,
-.000141,-.004997,
.000149,-.004997,
.00044,-.00498,
.000729,-.004946,
.001015,-.004895,
.00129,-.00483,
.00044,-.00398,
0.0*
4,1,15,-.00398,-.00044,
-.003999,-.000208,
-.004004,.000025,
-.003996,.000258,
-.00398,.00044,
-.00483,.00129,
-.004897,.001007,
-.004947,.000721,
-.004981,.000432,
-.004997,.000141,
-.004997,-.000149,
-.00498,-.00044,
-.004946,-.000729,
-.004895,-.001015,
-.00483,-.00129,
-.00398,-.00044,
0.0*
4,1,15,-.00044,.00398,
-.000208,.003999,
.000025,.004004,
.000258,.003996,
.00044,.00398,
.00129,.00483,
.001007,.004897,
.000721,.004947,
.000432,.004981,
.000141,.004997,
-.000149,.004997,
-.00044,.00498,
-.000729,.004946,
-.001015,.004895,
-.00129,.00483,
-.00044,.00398,
0.0*
%
%ADD11MACRO11*%
%AMMACRO18*
4,1,17,.09314,.06486,
.102988,.047701,
.109706,.029093,
.113092,.0096,
.113041,-.010184,
.109555,-.029658,
.10274,-.048232,
.09314,-.06486,
.09673,-.06845,
.107147,-.050613,
.114308,-.031238,
.117996,-.010914,
.118098,.009741,
.114613,.030101,
.107644,.049546,
.097406,.067485,
.09673,.06845,
.09314,.06486,
270.*
4,1,17,.06486,-.09314,
.047701,-.102988,
.029093,-.109706,
.0096,-.113092,
-.010184,-.113041,
-.029658,-.109555,
-.048232,-.10274,
-.06486,-.09314,
-.06845,-.09673,
-.050613,-.107147,
-.031238,-.114308,
-.010914,-.117996,
.009741,-.118098,
.030101,-.114613,
.049546,-.107644,
.067485,-.097406,
.06845,-.09673,
.06486,-.09314,
270.*
4,1,17,-.09314,-.06486,
-.102988,-.047701,
-.109706,-.029093,
-.113092,-.0096,
-.113041,.010184,
-.109555,.029658,
-.10274,.048232,
-.09314,.06486,
-.09673,.06845,
-.107147,.050613,
-.114308,.031238,
-.117996,.010914,
-.118098,-.009741,
-.114613,-.030101,
-.107644,-.049546,
-.097406,-.067485,
-.09673,-.06845,
-.09314,-.06486,
270.*
4,1,17,-.06486,.09314,
-.047701,.102988,
-.029093,.109706,
-.0096,.113092,
.010184,.113041,
.029658,.109555,
.048232,.10274,
.06486,.09314,
.06845,.09673,
.050613,.107147,
.031238,.114308,
.010914,.117996,
-.009741,.118098,
-.030101,.114613,
-.049546,.107644,
-.067485,.097406,
-.06845,.09673,
-.06486,.09314,
270.*
%
%ADD18MACRO18*%
%AMMACRO25*
4,1,13,.02594,.0118,
.027595,.007116,
.028411,.002216,
.028365,-.002751,
.027456,-.007635,
.02594,-.0118,
.02968,-.01554,
.031928,-.01015,
.033205,-.004452,
.033474,.001382,
.032725,.007174,
.030982,.012747,
.02968,.01554,
.02594,.0118,
270.*
4,1,13,.0118,-.02594,
.007116,-.027595,
.002216,-.028411,
-.002751,-.028365,
-.007635,-.027456,
-.0118,-.02594,
-.01554,-.02968,
-.01015,-.031928,
-.004452,-.033205,
.001382,-.033474,
.007174,-.032725,
.012747,-.030982,
.01554,-.02968,
.0118,-.02594,
270.*
4,1,13,-.02594,-.0118,
-.027595,-.007116,
-.028411,-.002216,
-.028365,.002751,
-.027456,.007635,
-.02594,.0118,
-.02968,.01554,
-.031928,.01015,
-.033205,.004452,
-.033474,-.001382,
-.032725,-.007174,
-.030982,-.012747,
-.02968,-.01554,
-.02594,-.0118,
270.*
4,1,13,-.0118,.02594,
-.007116,.027595,
-.002216,.028411,
.002751,.028365,
.007635,.027456,
.0118,.02594,
.01554,.02968,
.01015,.031928,
.004452,.033205,
-.001382,.033474,
-.007174,.032725,
-.012747,.030982,
-.01554,.02968,
-.0118,.02594,
270.*
%
%ADD25MACRO25*%
%ADD13C,.107*%
%ADD29C,.225*%
%ADD12C,.186*%
%ADD10C,.168*%
%AMMACRO19*
4,1,13,.02442,.01028,
.025834,.005883,
.026463,.001308,
.026288,-.003307,
.025315,-.007822,
.02442,-.01028,
.02819,-.01405,
.030201,-.008941,
.031295,-.003561,
.031438,.001927,
.030626,.007357,
.028883,.012564,
.02819,.01405,
.02442,.01028,
90.*
4,1,13,.01028,-.02442,
.005883,-.025834,
.001308,-.026463,
-.003307,-.026288,
-.007822,-.025315,
-.01028,-.02442,
-.01405,-.02819,
-.008941,-.030201,
-.003561,-.031295,
.001927,-.031438,
.007357,-.030626,
.012564,-.028883,
.01405,-.02819,
.01028,-.02442,
90.*
4,1,13,-.02442,-.01028,
-.025834,-.005883,
-.026463,-.001308,
-.026288,.003307,
-.025315,.007822,
-.02442,.01028,
-.02819,.01405,
-.030201,.008941,
-.031295,.003561,
-.031438,-.001927,
-.030626,-.007357,
-.028883,-.012564,
-.02819,-.01405,
-.02442,-.01028,
90.*
4,1,13,-.01028,.02442,
-.005883,.025834,
-.001308,.026463,
.003307,.026288,
.007822,.025315,
.01028,.02442,
.01405,.02819,
.008941,.030201,
.003561,.031295,
-.001927,.031438,
-.007357,.030626,
-.012564,.028883,
-.01405,.02819,
-.01028,.02442,
90.*
%
%ADD19MACRO19*%
%AMMACRO27*
4,1,14,.02819,.01405,
.030201,.008941,
.031295,.003561,
.031438,-.001927,
.030626,-.007357,
.028883,-.012564,
.02819,-.01405,
.03189,-.01775,
.034488,-.011943,
.036038,-.005773,
.036493,.000573,
.035839,.006901,
.034096,.01302,
.03189,.01775,
.02819,.01405,
0.0*
4,1,14,.01405,-.02819,
.008941,-.030201,
.003561,-.031295,
-.001927,-.031438,
-.007357,-.030626,
-.012564,-.028883,
-.01405,-.02819,
-.01775,-.03189,
-.011943,-.034488,
-.005773,-.036038,
.000573,-.036493,
.006901,-.035839,
.01302,-.034096,
.01775,-.03189,
.01405,-.02819,
0.0*
4,1,14,-.02819,-.01405,
-.030201,-.008941,
-.031295,-.003561,
-.031438,.001927,
-.030626,.007357,
-.028883,.012564,
-.02819,.01405,
-.03189,.01775,
-.034488,.011943,
-.036038,.005773,
-.036493,-.000573,
-.035839,-.006901,
-.034096,-.01302,
-.03189,-.01775,
-.02819,-.01405,
0.0*
4,1,14,-.01405,.02819,
-.008941,.030201,
-.003561,.031295,
.001927,.031438,
.007357,.030626,
.012564,.028883,
.01405,.02819,
.01775,.03189,
.011943,.034488,
.005773,.036038,
-.000573,.036493,
-.006901,.035839,
-.01302,.034096,
-.01775,.03189,
-.01405,.02819,
0.0*
%
%ADD27MACRO27*%
%AMMACRO23*
4,1,14,.0575,.02922,
.0617,.018791,
.064026,.007792,
.064406,-.003445,
.06283,-.014576,
.059344,-.025265,
.0575,-.02922,
.06121,-.03292,
.065997,-.021791,
.068778,-.01,
.069469,.002095,
.06805,.014127,
.064563,.025729,
.06121,.03292,
.0575,.02922,
0.0*
4,1,14,.02922,-.0575,
.018791,-.0617,
.007792,-.064026,
-.003445,-.064406,
-.014576,-.06283,
-.025265,-.059344,
-.02922,-.0575,
-.03292,-.06121,
-.021791,-.065997,
-.01,-.068778,
.002095,-.069469,
.014127,-.06805,
.025729,-.064563,
.03292,-.06121,
.02922,-.0575,
0.0*
4,1,14,-.0575,-.02922,
-.0617,-.018791,
-.064026,-.007792,
-.064406,.003445,
-.06283,.014576,
-.059344,.025265,
-.0575,.02922,
-.06121,.03292,
-.065997,.021791,
-.068778,.01,
-.069469,-.002095,
-.06805,-.014127,
-.064563,-.025729,
-.06121,-.03292,
-.0575,-.02922,
0.0*
4,1,14,-.02922,.0575,
-.018791,.0617,
-.007792,.064026,
.003445,.064406,
.014576,.06283,
.025265,.059344,
.02922,.0575,
.03292,.06121,
.021791,.065997,
.01,.068778,
-.002095,.069469,
-.014127,.06805,
-.025729,.064563,
-.03292,.06121,
-.02922,.0575,
0.0*
%
%ADD23MACRO23*%
%ADD30C,.02*%
%ADD31C,.006*%
%ADD35C,.08506*%
%ADD34C,.08606*%
%ADD33C,.10306*%
%ADD32C,.18206*%
G75*
%LPD*%
G75*
G36*
G01X-149740Y-6000D02*
X795764D01*
Y931197D01*
X-149740D01*
Y-6000D01*
G37*
%LPC*%
G75*
G36*
G01X3000Y209904D02*
X2866Y210037D01*
X2854Y210095D01*
G03X-2503Y215452I-6791J-1434D01*
G01X-2561Y215464D01*
X-2694Y215598D01*
X-3704D01*
G03X-3937Y215602I-236J-6937D01*
G01X-139803D01*
G02X-140736Y216535I0J933D01*
G01Y338583D01*
G02X-139803Y339516I933J0D01*
G01X-62992D01*
G03X-62759Y339520I-3J6941D01*
G01X-61749D01*
X-61616Y339654D01*
X-61558Y339666D01*
G03X-56201Y345023I-1434J6791D01*
G01X-56189Y345081D01*
X-56055Y345214D01*
Y346224D01*
G03X-56051Y346457I-6937J236D01*
G01Y503937D01*
G02X-55118Y504870I933J0D01*
G01X-3937D01*
G03X-3704Y504874I-3J6941D01*
G01X-2694D01*
X-2560Y505008D01*
X-2502Y505020D01*
G03X2854Y510376I-1435J6791D01*
G01X2866Y510434D01*
X3000Y510568D01*
Y511578D01*
G03X3004Y511811I-6937J236D01*
G01Y783465D01*
G02X3937Y784398I933J0D01*
G01X74803D01*
G03X75036Y784402I-3J6941D01*
G01X76046D01*
X76179Y784536D01*
X76237Y784548D01*
G03X81594Y789905I-1434J6791D01*
G01X81606Y789963D01*
X81740Y790096D01*
Y791106D01*
G03X81744Y791339I-6937J236D01*
G01Y921260D01*
G02X82677Y922193I933J0D01*
G01X755906D01*
G02X756839Y921260I0J-933D01*
G01Y869144D01*
X725646D01*
X657169Y800667D01*
Y640965D01*
X414748Y398544D01*
X414630Y398583D01*
G03X411717Y395670I-730J-2183D01*
G01X411756Y395552D01*
X387178Y370974D01*
G02X386495Y371257I-283J283D01*
G01Y508915D01*
X351410Y544000D01*
X219730D01*
X210380Y534650D01*
X53191D01*
X53163Y534817D01*
G03X48623I-2270J-383D01*
G01X48595Y534650D01*
X33589D01*
X29550Y530611D01*
Y509989D01*
X31889Y507650D01*
X57550D01*
Y492111D01*
X55950Y490511D01*
X55937Y394135D01*
X59450Y390622D01*
Y389711D01*
X11450Y341711D01*
Y121289D01*
X15589Y117150D01*
X36389D01*
X38150Y115389D01*
Y37589D01*
X47489Y28250D01*
X68048D01*
G03X68567Y28458I1J750D01*
G02X84971Y28464I8205J-8572D01*
G01X85684Y27750D01*
X92811D01*
X95150Y30089D01*
Y56889D01*
X97111Y58850D01*
X171511D01*
X173650Y60989D01*
Y117750D01*
X195590D01*
X222690Y90750D01*
X230189D01*
X232750Y88189D01*
Y83189D01*
X290398Y25541D01*
X381056D01*
X387793Y32278D01*
Y44385D01*
X380314Y51863D01*
X307810Y51750D01*
X211750Y147811D01*
Y175311D01*
X199811Y187250D01*
X87289D01*
X83889Y183850D01*
X69111D01*
X67050Y185911D01*
Y208500D01*
X67026Y314286D01*
X70444Y317704D01*
X222527D01*
X252077Y347254D01*
X364519D01*
Y282606D01*
X318229Y236316D01*
X99776D01*
X99745Y236347D01*
X96324D01*
X78156Y218179D01*
Y202916D01*
X80491Y200581D01*
X95650D01*
X106604Y211535D01*
X343179D01*
X405662Y274018D01*
Y328790D01*
X724010Y647138D01*
X773015D01*
Y382724D01*
X770786D01*
X770782Y382728D01*
X765945D01*
G03Y369240I0J-6744D01*
G01X770062D01*
X770066Y369244D01*
X773015D01*
Y331150D01*
X767436D01*
X767432Y331154D01*
X763780D01*
G03X763547Y331150I3J-6941D01*
G01X762537D01*
X762404Y331016D01*
X762346Y331004D01*
G03X756989Y325647I1434J-6791D01*
G01X756977Y325589D01*
X756843Y325456D01*
Y324446D01*
G03X756839Y324213I6937J-236D01*
G01Y3937D01*
G02X755906Y3004I-933J0D01*
G01X3937D01*
G02X3004Y3937I0J933D01*
G01Y208661D01*
G03X3000Y208894I-6941J-3D01*
G01Y209904D01*
G37*
G36*
G01X166659Y409308D02*
X166696Y409424D01*
G03X164808Y411312I-1430J458D01*
G01X164692Y411275D01*
X162592Y413375D01*
X162648Y413501D01*
G03X160664Y415485I-1371J613D01*
G01X160538Y415429D01*
X158659Y417308D01*
X158728Y417439D01*
G03X156697Y419470I-1327J704D01*
G01X156566Y419401D01*
X154816Y421151D01*
X154883Y421281D01*
G03X152858Y423306I-1334J691D01*
G01X152728Y423239D01*
X150879Y425088D01*
X150946Y425218D01*
G03X148921Y427243I-1334J691D01*
G01X148791Y427176D01*
X146942Y429025D01*
X147009Y429155D01*
G03X144984Y431180I-1334J691D01*
G01X144854Y431113D01*
X144197Y431770D01*
X144157D01*
X141830Y434097D01*
X135340D01*
X135296Y434237D01*
G03X132432I-1432J-454D01*
G01X132388Y434097D01*
X117788D01*
X114855Y431164D01*
X114726Y431227D01*
G03X112715Y429216I-663J-1348D01*
G01X112778Y429087D01*
X110901Y427210D01*
X110785Y427246D01*
G03X108900Y425361I-453J-1432D01*
G01X108936Y425245D01*
X108528Y424837D01*
X105363D01*
X104099Y426101D01*
X104090Y426169D01*
G03X103156Y427378I-1490J-186D01*
G01X103030Y427429D01*
Y428495D01*
X103128Y428553D01*
G03Y431139I-764J1293D01*
G01X103030Y431197D01*
Y444202D01*
X103166Y444248D01*
G03X103543Y446903I-482J1423D01*
G02X103489Y447514I229J328D01*
G01X105389Y449414D01*
X131143D01*
X135791Y444766D01*
X136547D01*
X136607Y444687D01*
G03X138995I1194J911D01*
G01X139055Y444766D01*
X139179D01*
X150404Y455991D01*
X150430Y456005D01*
G03X151042Y456617I-711J1323D01*
G01X151056Y456643D01*
X154039Y459626D01*
X154082Y459641D01*
G03X155000Y460559I-499J1417D01*
G01X155015Y460602D01*
X161525Y467112D01*
Y467712D01*
X161690Y467742D01*
G03Y470698I-267J1478D01*
G01X161525Y470728D01*
Y471649D01*
X161690Y471679D01*
G03Y474635I-267J1478D01*
G01X161525Y474665D01*
Y475586D01*
X161690Y475616D01*
G03Y478572I-267J1478D01*
G01X161525Y478602D01*
Y479523D01*
X161690Y479553D01*
G03Y482509I-267J1478D01*
G01X161525Y482539D01*
Y483460D01*
X161690Y483490D01*
G03X162814Y485535I-267J1478D01*
G01X162763Y485658D01*
X164670Y487565D01*
X164793Y487514D01*
G03X166751Y489472I567J1391D01*
G01X166700Y489595D01*
X168607Y491502D01*
X168730Y491451D01*
G03X170306Y491729I567J1391D01*
G01X170363Y491781D01*
X177585D01*
X177615Y491771D01*
G03X178553I469J1427D01*
G01X178583Y491781D01*
X225071D01*
X235763Y502473D01*
X261237D01*
X267895Y509131D01*
Y515616D01*
X264561Y518950D01*
X223864D01*
X214064Y509150D01*
X32511D01*
X31050Y510611D01*
Y529989D01*
X34211Y533150D01*
X48980D01*
X49040Y533069D01*
G03X52746I1853J1365D01*
G01X52806Y533150D01*
X211002D01*
X220352Y542500D01*
X350788D01*
X384995Y508293D01*
Y463476D01*
X384983Y463442D01*
G03Y461852I2160J-795D01*
G01X384995Y461818D01*
Y368791D01*
X364958Y348754D01*
X251455D01*
X221905Y319204D01*
X69822D01*
X65526Y314908D01*
X65550Y208500D01*
Y185289D01*
X68489Y182350D01*
X83650D01*
Y155689D01*
X87489Y151850D01*
X161589D01*
X169250Y144189D01*
Y121089D01*
X172150Y118189D01*
Y61611D01*
X170889Y60350D01*
X96489D01*
X93650Y57511D01*
Y30711D01*
X92189Y29250D01*
X86306D01*
X86025Y29530D01*
X86022Y29533D01*
G03X86014Y29542I-564J-493D01*
G03X67809Y29802I-9242J-9656D01*
G01X67752Y29750D01*
X48111D01*
X39650Y38211D01*
Y116011D01*
X37011Y118650D01*
X16211D01*
X12950Y121911D01*
Y341089D01*
X28290Y356429D01*
X28319Y356444D01*
G03X29340Y357465I-1035J2056D01*
G01X29355Y357494D01*
X43601Y371740D01*
X43682Y371741D01*
G03X45941Y374000I-43J2302D01*
G01X45942Y374081D01*
X60950Y389089D01*
Y390350D01*
X66189D01*
X68589Y387950D01*
X86686D01*
X88179Y386437D01*
X152885D01*
X166914Y372408D01*
X213233D01*
X215706Y374881D01*
Y390421D01*
X209165Y396962D01*
X209170Y397051D01*
G03X206308Y399409I-2299J126D01*
G01X206284Y399403D01*
X182311D01*
X182252Y399494D01*
G03X179730I-1261J-816D01*
G01X179671Y399403D01*
X176564D01*
X166659Y409308D01*
G37*
G36*
G01X110135Y424322D02*
X110226Y424316D01*
G03X111830Y425920I106J1498D01*
G01X111824Y426011D01*
X114194Y428381D01*
X114261Y428390D01*
G03X115552Y429681I-198J1489D01*
G01X115561Y429748D01*
X118410Y432597D01*
X132940D01*
X132992Y432560D01*
G03X134736I872J1223D01*
G01X134788Y432597D01*
X141208D01*
X143510Y430295D01*
X143550D01*
X144183Y429662D01*
X144193Y429599D01*
G03X145428Y428364I1482J247D01*
G01X145491Y428354D01*
X148120Y425725D01*
X148130Y425662D01*
G03X149365Y424427I1482J247D01*
G01X149428Y424417D01*
X152057Y421788D01*
X152067Y421725D01*
G03X153302Y420490I1482J247D01*
G01X153365Y420480D01*
X155913Y417932D01*
X155924Y417871D01*
G03X157129Y416666I1477J272D01*
G01X157190Y416655D01*
X159774Y414071D01*
X159780Y413998D01*
G03X161161Y412617I1497J116D01*
G01X161234Y412611D01*
X163773Y410072D01*
X163767Y409981D01*
G03X165365Y408383I1499J-99D01*
G01X165456Y408389D01*
X175942Y397903D01*
X179700D01*
X179760Y397818D01*
G03X182222I1231J860D01*
G01X182282Y397903D01*
X204189D01*
G02X204586Y397455I0J-400D01*
G03X208342Y395406I2285J-278D01*
G01X208482Y395523D01*
X214206Y389799D01*
Y375503D01*
X212611Y373908D01*
X167536D01*
X153507Y387937D01*
X88807D01*
X87316Y389448D01*
X87212Y389449D01*
X87211Y389450D01*
X87002D01*
X86694Y389452D01*
X86692Y389450D01*
X69211D01*
X66811Y391850D01*
X60344D01*
X57437Y394757D01*
X57450Y489889D01*
X59050Y491489D01*
Y507650D01*
X214284D01*
X214803Y507767D01*
X224486Y517450D01*
X263939D01*
X266395Y514994D01*
Y509753D01*
X260615Y503973D01*
X235141D01*
X224449Y493281D01*
X179593D01*
X179565Y493448D01*
G03X176603I-1481J-250D01*
G01X176575Y493281D01*
X170740D01*
X170689Y493406D01*
G03X167796Y492889I-1392J-564D01*
G01X167793Y492810D01*
X165392Y490409D01*
X165313Y490406D01*
G03X163859Y488952I47J-1501D01*
G01X163856Y488873D01*
X161455Y486472D01*
X161376Y486469D01*
G03X160013Y484451I47J-1501D01*
G01X160025Y484418D01*
Y481581D01*
X160013Y481548D01*
G03Y480514I1410J-517D01*
G01X160025Y480481D01*
Y477644D01*
X160013Y477611D01*
G03Y476577I1410J-517D01*
G01X160025Y476544D01*
Y473707D01*
X160013Y473674D01*
G03Y472640I1410J-517D01*
G01X160025Y472607D01*
Y469770D01*
X160013Y469737D01*
G03Y468703I1410J-517D01*
G01X160025Y468670D01*
Y467734D01*
X154528Y462237D01*
X154392Y462323D01*
G03X152318Y460249I-809J-1265D01*
G01X152404Y460113D01*
X150737Y458446D01*
X150599Y458545D01*
G03X148502Y456448I-880J-1217D01*
G01X148601Y456310D01*
X138914Y446623D01*
X138774Y446743D01*
G03X136680Y446597I-972J-1145D01*
G02X136098Y446581I-299J266D01*
G01X131765Y450914D01*
X104767D01*
X101530Y447677D01*
Y446635D01*
X101489Y446581D01*
G03Y444761I1195J-910D01*
G01X101530Y444707D01*
Y431099D01*
X101452Y431039D01*
G03Y428653I912J-1193D01*
G01X101530Y428593D01*
Y427040D01*
X101479Y426983D01*
G03X103256Y424632I1121J-1000D01*
G01X103384Y424694D01*
X104741Y423337D01*
X109150D01*
X110135Y424322D01*
G37*
G36*
G01X380434Y27041D02*
X291020D01*
X234250Y83811D01*
Y88811D01*
X230811Y92250D01*
X223310D01*
X196210Y119250D01*
X173211D01*
X170750Y121711D01*
Y144811D01*
X162211Y153350D01*
X88111D01*
X85150Y156311D01*
Y182989D01*
X87911Y185750D01*
X199189D01*
X210250Y174689D01*
Y147189D01*
X307190Y50250D01*
X379694Y50363D01*
X386293Y43763D01*
Y32900D01*
X380434Y27041D01*
G37*
G36*
G01X81113Y202081D02*
X79656Y203538D01*
Y217557D01*
X96946Y234847D01*
X98686D01*
X98717Y234816D01*
X318851D01*
X366019Y281984D01*
Y347693D01*
X412735Y394409D01*
X412864Y394344D01*
G03X415956Y397436I1036J2056D01*
G01X415891Y397565D01*
X658669Y640343D01*
Y800045D01*
X726268Y867644D01*
X756839D01*
Y821457D01*
G03X763780Y814516I6941J0D01*
G01X767612D01*
X767616Y814520D01*
X773015D01*
Y792173D01*
X771286D01*
X771282Y792177D01*
X765945D01*
G03Y778689I0J-6744D01*
G01X772462D01*
X772466Y778693D01*
X773015D01*
Y740602D01*
X763780D01*
G03X756839Y733661I0J-6941D01*
G01Y663976D01*
G03X763780Y657035I6941J0D01*
G01X765572D01*
X765576Y657039D01*
X773015D01*
Y648638D01*
X723388D01*
X632221Y557471D01*
X632161Y557460D01*
G03X630340Y555639I439J-2260D01*
G01X630329Y555579D01*
X404162Y329412D01*
Y274640D01*
X342557Y213035D01*
X223993D01*
X223958Y213048D01*
G03X222300I-829J-2147D01*
G01X222265Y213035D01*
X221106D01*
X221054Y213072D01*
G03X218380I-1337J-1874D01*
G01X218328Y213035D01*
X105982D01*
X95028Y202081D01*
X81113D01*
G37*
%LPD*%
G75*
G36*
G01X708866Y31408D02*
X708859Y31414D01*
X708852Y31421D01*
G02X708179Y32132I7684J7948D01*
G01X708148Y32166D01*
X708120Y32201D01*
G02X706495Y34742I8414J7171D01*
G01X706486Y34761D01*
X706480Y34776D01*
G02X705946Y36193I10054J4598D01*
G01X705945Y36197D01*
X705944Y36202D01*
G02X705542Y38197I10590J3172D01*
G01X705541Y38207D01*
X705540Y38220D01*
G02X706596Y44211I10995J1151D01*
G01X706602Y44223D01*
G02X708278Y46721I9933J-4853D01*
G01X708318Y46768D01*
X708364Y46816D01*
G02X710669Y48740I8171J-7446D01*
G01X710671Y48742D01*
G02X712010Y49457I5865J-9372D01*
G01X712040Y49471D01*
X712070Y49483D01*
G02X712988Y49841I4472J-10110D01*
G01X712996Y49843D01*
G02X720074I3539J-10473D01*
G01X720082Y49841D01*
G02X721000Y49483I-3554J-10468D01*
G01X721030Y49471D01*
X721060Y49457D01*
G02X722399Y48742I-4526J-10087D01*
G01X722401Y48740D01*
G02X724706Y46816I-5866J-9370D01*
G01X724752Y46768D01*
X724792Y46721D01*
G02X726468Y44223I-8257J-7351D01*
G01X726474Y44211D01*
G02X727530Y38220I-9939J-4840D01*
G01X727529Y38207D01*
X727528Y38197D01*
G02X727126Y36202I-10992J1177D01*
G01X727125Y36197D01*
X727124Y36193D01*
G02X726590Y34776I-10588J3181D01*
G01X726584Y34761D01*
X726575Y34742D01*
G02X724950Y32201I-10039J4630D01*
G01X724922Y32166D01*
X724891Y32132D01*
G02X724218Y31421I-8357J7237D01*
G01X724211Y31414D01*
X724204Y31408D01*
G02X708866I-7669J7962D01*
G37*
G54D35*
X144843Y812994D03*
Y860234D03*
G54D34*
X54724Y557087D03*
Y620079D03*
Y675197D03*
Y738189D03*
X144843Y798779D03*
Y874449D03*
G54D33*
X-33503Y269685D03*
G54D32*
X-59094Y277559D03*
X-7913D03*
G54D15*
X8789Y376072D03*
X6944Y414616D03*
X6855Y436844D03*
X6750Y425868D03*
X7180Y449205D03*
X62439Y413744D03*
X66931Y398350D03*
X74863Y390483D03*
X64055Y389700D03*
X33722Y401639D03*
X74544Y414071D03*
X70779Y402387D03*
X79016Y410283D03*
X35738Y406956D03*
X14422Y411528D03*
X14657Y416838D03*
X10615Y411073D03*
X26551Y394546D03*
X30232Y416556D03*
X23922Y415548D03*
X35994Y410146D03*
X43719Y414419D03*
X32141Y407501D03*
X31808Y410684D03*
X18448Y402542D03*
X74817Y409752D03*
X26972Y399588D03*
X70882Y409794D03*
X66938Y410045D03*
X78939Y414083D03*
X18448Y406788D03*
X53976Y389814D03*
X74894Y398251D03*
X62031Y399713D03*
X70775Y398396D03*
X70845Y405839D03*
X70952Y414050D03*
X70865Y390502D03*
X74702Y394300D03*
X74869Y406315D03*
X78300Y386505D03*
X64948Y386626D03*
X78362Y398337D03*
X77963Y381183D03*
X70888Y394222D03*
X66963Y473083D03*
X66931Y484968D03*
X79081Y465348D03*
X70704Y429620D03*
X67015Y449433D03*
X74639Y441855D03*
X78754Y453353D03*
X78811Y426113D03*
X52151Y456887D03*
X66903Y457689D03*
X78798Y433983D03*
X17072Y435057D03*
X74836Y453477D03*
X59980Y482517D03*
X78754Y449904D03*
X67112Y481066D03*
X70488Y465291D03*
X74450Y457429D03*
X70713Y461504D03*
X36237Y441728D03*
X70908Y457771D03*
X70898Y418271D03*
X61038Y424878D03*
X74726Y425594D03*
X59209Y438908D03*
X46853Y441796D03*
X78561Y421756D03*
X70809Y438057D03*
X43659Y432766D03*
X43088Y438073D03*
X45486Y456341D03*
X38566Y451290D03*
X42312Y463368D03*
X74780Y429794D03*
X24357Y423051D03*
X37988Y438328D03*
X19757Y418538D03*
X29472Y428016D03*
X78738Y429679D03*
X11964Y421332D03*
X52476Y439395D03*
X13062Y429279D03*
X74656Y421838D03*
X17936Y431103D03*
X14206Y433632D03*
X15424Y422722D03*
X70857Y433857D03*
X19015Y426461D03*
X14147Y438989D03*
X74752Y437655D03*
X74437Y473159D03*
X15872Y441916D03*
X74460Y461287D03*
X78793Y445704D03*
X70868Y477094D03*
X23748Y436249D03*
X26611Y441743D03*
X70909Y469595D03*
X30513Y437850D03*
X74702Y469183D03*
X37420Y461517D03*
X31517Y445328D03*
X70868Y473157D03*
X28472Y447107D03*
X48298Y454813D03*
X70602Y453533D03*
X79050Y457367D03*
X74805Y481031D03*
X66991Y476766D03*
X62798Y461555D03*
X74451Y465323D03*
X79094Y441620D03*
X74801Y433368D03*
X70869Y421840D03*
X70759Y449277D03*
X74805Y477094D03*
X70868Y481031D03*
X74598Y485021D03*
X78421Y473078D03*
X74695Y449260D03*
X59063Y485583D03*
X79134Y461339D03*
X78742Y488905D03*
X66961Y488885D03*
X74805Y492842D03*
X74870Y488789D03*
X69523Y567387D03*
X69555Y564187D03*
X69599Y601527D03*
X69569Y598159D03*
X69388Y576660D03*
X69450Y573460D03*
X69569Y608021D03*
X69496Y611417D03*
X69661Y591387D03*
X66579Y592250D03*
X63125Y592801D03*
X62681Y589462D03*
X69451Y684303D03*
Y681103D03*
Y691003D03*
X69474Y694403D03*
X69523Y718313D03*
Y715113D03*
X69472Y729385D03*
X69548Y726185D03*
X145771Y414191D03*
X82555Y406288D03*
X110472Y394496D03*
X145765Y406438D03*
X122053Y406224D03*
X114175Y410161D03*
X125990Y394413D03*
X141738D03*
X98427Y414098D03*
X125990D03*
X90553Y410161D03*
X102263Y414083D03*
X141887Y410202D03*
X102364Y406224D03*
X133864Y410161D03*
X94367Y394479D03*
X102364Y402287D03*
X106301Y398350D03*
Y402287D03*
X102364Y398350D03*
X110238Y402287D03*
X114175D03*
X110238Y398350D03*
X114175D03*
X85721Y385798D03*
X149362Y413951D03*
X149498Y406396D03*
X145795Y410173D03*
X149431Y394402D03*
X149783Y390487D03*
X110238Y410161D03*
X141738Y414098D03*
X133863Y413773D03*
X114175Y414098D03*
X122053D03*
X125990Y410161D03*
X94579Y406324D03*
X118130Y398511D03*
X98427Y410161D03*
X90553Y414098D03*
X86563Y402383D03*
X133964Y394555D03*
X102555Y394412D03*
X86616Y394413D03*
X86463Y390483D03*
X149663Y410083D03*
X82459Y413976D03*
X90566Y394383D03*
X82663Y402406D03*
X133864Y402287D03*
X86772Y414047D03*
X122053Y402287D03*
X133864Y398350D03*
X137801D03*
X122053D03*
X137801Y402287D03*
X125990D03*
Y398350D03*
X129927Y402287D03*
Y398350D03*
X82663Y398383D03*
X141738Y402287D03*
Y398350D03*
X145865Y402287D03*
Y398350D03*
X149488Y402114D03*
X149583Y398383D03*
X90359Y469275D03*
X137801Y453472D03*
Y445598D03*
X133864Y437720D03*
Y445598D03*
X133953Y425813D03*
X102684Y445671D03*
X106263Y437583D03*
X133864Y433783D03*
X102364Y429846D03*
X98363Y421883D03*
X94263Y418129D03*
X106210Y421976D03*
X110332Y425814D03*
X149612Y445598D03*
Y433783D03*
X86493Y441401D03*
X86616Y433783D03*
X86687Y421669D03*
X137801Y477094D03*
X149612D03*
X114175D03*
X102364D03*
X98626Y477049D03*
X130081Y425912D03*
X121943Y425834D03*
X114091Y425962D03*
X122053Y421972D03*
Y418035D03*
X106301D03*
X114175D03*
X133863Y417883D03*
X110222Y417989D03*
X82564Y449659D03*
X145663Y441483D03*
X98288Y441609D03*
X149612Y429846D03*
X110238Y453472D03*
X122053Y429846D03*
X114063Y429879D03*
X125897Y453240D03*
X118238Y453417D03*
X149594Y480923D03*
X94518Y449186D03*
X86768Y449383D03*
X98427Y484968D03*
Y481031D03*
X102364D03*
Y484968D03*
X106301D03*
Y481031D03*
X114175Y484968D03*
Y481031D03*
X122053Y484968D03*
Y481031D03*
X125990Y484968D03*
Y481031D03*
X145567Y453547D03*
X145763Y449583D03*
X149576Y465497D03*
X98597Y457291D03*
X94490Y429846D03*
X90463Y425983D03*
X90480Y437608D03*
X82562Y425980D03*
X86505Y425987D03*
X90380Y429650D03*
X130080Y457372D03*
X94490Y437720D03*
X82681Y430041D03*
X141827Y461346D03*
X98334Y429754D03*
X98427Y437720D03*
X94369Y425977D03*
X82677Y433595D03*
X149563Y469220D03*
X94490Y433783D03*
X141738Y481031D03*
X82663Y457486D03*
X141738Y484968D03*
X98433Y449125D03*
X137801Y481031D03*
X102600Y425983D03*
X137801Y484968D03*
X94554Y421911D03*
X133864Y481031D03*
X149612Y437720D03*
X94414Y445605D03*
X133864Y484968D03*
X86663Y429536D03*
X82542Y445403D03*
X98427Y433783D03*
X86568Y445669D03*
X90426Y449431D03*
X90563Y417983D03*
X145675Y425909D03*
X82573Y441360D03*
X145675Y437720D03*
X98280Y445405D03*
X90426Y441880D03*
X145675Y481031D03*
Y484968D03*
X145737Y418077D03*
X145675Y473157D03*
Y465283D03*
X149719Y457328D03*
X129927Y473157D03*
Y465283D03*
X137801Y461346D03*
Y457409D03*
X114175Y473157D03*
X122053Y469220D03*
X110263Y469083D03*
X122053Y473157D03*
X90350Y473069D03*
X82679Y477094D03*
X90662Y461604D03*
X106263Y453483D03*
X106449Y465157D03*
X122053Y445598D03*
X126180Y418224D03*
X137801Y437720D03*
X137767Y425993D03*
X129927Y445598D03*
X141738Y449535D03*
X133864Y421972D03*
Y429846D03*
X98533Y418180D03*
X118134Y449362D03*
X106363Y441583D03*
X110238Y445598D03*
X110289Y422113D03*
X122053Y437720D03*
X114175D03*
X94661Y441681D03*
X106263Y433683D03*
X90544Y433408D03*
X90408Y421930D03*
X129927Y437720D03*
X141738Y429846D03*
X86663Y453583D03*
X82732Y453139D03*
X149612Y425909D03*
X82535Y461227D03*
X83021Y473118D03*
X141595Y421932D03*
X141775Y426153D03*
X86735Y461382D03*
X141763Y437883D03*
X86937Y477160D03*
X141682Y417902D03*
X82759Y469436D03*
X145663Y445583D03*
X145675Y429846D03*
X142008Y457429D03*
X141863Y445583D03*
X86959Y469276D03*
X137570Y421843D03*
X145561Y421879D03*
X90965Y465270D03*
X129927Y481031D03*
Y484968D03*
X110238Y481031D03*
Y484968D03*
X94490Y481031D03*
X86663Y457283D03*
X94490Y484968D03*
X86765Y465205D03*
X138061Y418151D03*
X145675Y433783D03*
X82763Y417750D03*
X86523Y417943D03*
X94844Y469182D03*
X102469Y469134D03*
X106149Y457371D03*
X141649Y453189D03*
X149620Y485149D03*
X98682Y461441D03*
X94092Y492819D03*
X141738Y488905D03*
X110238D03*
X125990D03*
X94377Y489070D03*
X91198Y595087D03*
X91123Y591887D03*
X91223Y588487D03*
X159768Y238444D03*
X160004Y233894D03*
X181576Y407810D03*
X175463Y413760D03*
X161499Y402554D03*
X169297Y402536D03*
X157502Y390427D03*
X173425Y390228D03*
X176751Y387090D03*
X157251Y414149D03*
X161477Y394511D03*
X180991Y398678D03*
X180809Y414170D03*
X179225Y403667D03*
X203410Y394323D03*
X182378Y390377D03*
X157574Y394185D03*
X161241Y398226D03*
X161277Y414114D03*
X174124Y402624D03*
X161213Y390551D03*
X169503Y386977D03*
X153587Y406496D03*
X157554Y402251D03*
X157698Y406313D03*
X161475Y410299D03*
X165266Y409882D03*
X165337Y414489D03*
X153528Y410052D03*
X165455Y398256D03*
X165229Y402019D03*
X157411Y398513D03*
X169113Y398299D03*
X178031Y390023D03*
X177588Y482616D03*
X161423Y469220D03*
X153583Y461058D03*
X169297Y477094D03*
Y465283D03*
X157486Y437720D03*
Y429846D03*
X153416Y445539D03*
X169290Y417960D03*
X169297Y437720D03*
X169112Y453260D03*
X169166Y429679D03*
X153549Y429846D03*
X165621Y418066D03*
X153549Y425909D03*
X161746Y421972D03*
X177182Y467018D03*
X175477Y472360D03*
X176815Y479061D03*
X161473Y457213D03*
X165360Y477094D03*
X153549Y437720D03*
X157560Y445484D03*
X153549Y449535D03*
X174859Y469220D03*
X157322Y453385D03*
X165317Y461561D03*
X165360Y473157D03*
X161455Y453385D03*
X177763Y486293D03*
X153463Y453383D03*
X157411Y469344D03*
X161423Y477094D03*
X157486Y461346D03*
X153690Y469111D03*
X165411Y429590D03*
X175161Y434723D03*
X161423Y445598D03*
X153549Y421972D03*
X161423Y484968D03*
Y481031D03*
X157486Y473157D03*
X165360Y469220D03*
X153549Y477094D03*
X173234Y465283D03*
Y453472D03*
X174086Y484839D03*
X175150Y476294D03*
X174351Y429014D03*
X161423Y437720D03*
X153549Y433783D03*
X161363Y425780D03*
X173234Y437720D03*
X173155Y417978D03*
X153422Y441722D03*
X161423Y449430D03*
X161670Y418161D03*
X176662Y418122D03*
X153201Y418097D03*
X157401Y418143D03*
X157463Y421883D03*
X157486Y425909D03*
X173458Y457178D03*
X178053Y474260D03*
X174601Y481467D03*
X165319Y453134D03*
X165353Y480812D03*
X157486Y433783D03*
X165360Y421972D03*
X153646Y457393D03*
X161294Y461561D03*
X165363Y425783D03*
X157393Y457572D03*
X165217Y457361D03*
X165355Y433382D03*
X161423Y473157D03*
X165355Y437582D03*
X165360Y445598D03*
X157411Y449556D03*
X169157Y445598D03*
X157508Y480990D03*
X165288Y449306D03*
X157486Y484968D03*
X153601Y480894D03*
X153586Y485118D03*
X161423Y433783D03*
X181414Y490281D03*
X174475Y488016D03*
X178084Y493198D03*
X157486Y488905D03*
X165360D03*
X169297Y492842D03*
X161423D03*
X159589Y817543D03*
X159688Y832484D03*
X159431Y838974D03*
X159688Y829234D03*
X159137Y820712D03*
X159688Y851564D03*
X159560Y842172D03*
X159426Y848357D03*
X662166Y456914D03*
X661760Y460089D03*
X646246Y475961D03*
X646794Y472634D03*
X682915Y467823D03*
X708059Y449951D03*
X671145Y454348D03*
X658195Y464248D03*
X653351Y470098D03*
X650837Y472421D03*
X646251Y479161D03*
X675745Y448189D03*
X735191Y453967D03*
X735231Y457167D03*
X746845Y476389D03*
Y473189D03*
X717993Y451389D03*
X731751Y464398D03*
X735259Y469898D03*
X721445Y455789D03*
X726589Y460909D03*
X743520Y478297D03*
X738745Y472789D03*
X713845Y447289D03*
G54D14*
X9243Y334400D03*
X8788Y453864D03*
X63400Y89300D03*
X51900Y83600D03*
X43980Y86200D03*
X68000Y87750D03*
X42700Y110500D03*
X67300Y107200D03*
X63100Y107300D03*
X48100Y133900D03*
X59200Y95573D03*
X51800Y93500D03*
X79600Y91500D03*
X51900Y89900D03*
X79500Y85700D03*
X77200Y95500D03*
X69800Y176800D03*
X31500Y185700D03*
X76250Y148850D03*
X70200Y199300D03*
X47900Y145500D03*
X48100Y153800D03*
X43800Y204800D03*
X38800Y194300D03*
X38700Y199700D03*
X49500Y169300D03*
X61751Y181464D03*
X44100Y200600D03*
X49286Y203671D03*
X60200Y193550D03*
X29600Y200100D03*
X26100Y187300D03*
X39800Y172900D03*
X27800Y191100D03*
X74700Y191700D03*
X70675Y145000D03*
X60009Y255077D03*
X55624Y255132D03*
X59523Y271123D03*
X60102Y263180D03*
X55883Y263570D03*
X33400Y266400D03*
X59258Y246890D03*
X60069Y237965D03*
X64700Y215100D03*
X51600Y217000D03*
X50500Y243100D03*
X70636Y272953D03*
X79189Y235119D03*
X43900Y209000D03*
X76019Y222534D03*
X42507Y296616D03*
X59316Y300366D03*
X59096Y289139D03*
X59523Y281330D03*
X52257Y276649D03*
X55420Y288656D03*
X17100Y311700D03*
X43181Y278603D03*
X39563Y307968D03*
X21876Y282289D03*
X41418Y287473D03*
X61776Y367194D03*
X43345Y386857D03*
X43639Y374043D03*
X29700Y355000D03*
X27284Y358500D03*
X67527Y381818D03*
X65605Y367307D03*
X51422Y473540D03*
X24315Y472668D03*
X47307Y465104D03*
X29064Y471345D03*
X55295Y479672D03*
X20928Y453864D03*
X21300Y468000D03*
X38800Y535700D03*
X38200Y528900D03*
X32026Y516764D03*
X60800Y505200D03*
X54659Y513125D03*
X67140Y511501D03*
X50893Y534434D03*
X67244Y535455D03*
X72677Y528615D03*
X59379Y644787D03*
X57500Y662600D03*
X47000Y645300D03*
X60122Y747800D03*
X64000Y765600D03*
X47100Y746000D03*
X65447Y711413D03*
X62066Y711051D03*
X65356Y707010D03*
X61193Y706973D03*
X106300Y105900D03*
X81150Y120850D03*
X89400Y120800D03*
X85250Y120850D03*
X117500Y106200D03*
X85000Y107800D03*
X111700Y106100D03*
X89000Y107700D03*
X82400Y89500D03*
X132500Y124600D03*
X83800Y188800D03*
X111482Y202800D03*
X113815Y194333D03*
X122400Y199000D03*
X80685Y192398D03*
X79900Y148700D03*
X103300Y160900D03*
X112000Y160700D03*
X119900Y162200D03*
X125300Y162300D03*
X107771Y182699D03*
X145400Y161955D03*
X114700Y157000D03*
X107672Y156597D03*
X98700Y156200D03*
X122200Y156700D03*
X80207Y139965D03*
X81200Y176000D03*
X93303Y154970D03*
X144950Y177338D03*
X85713Y151540D03*
X84900Y145300D03*
X125700Y225200D03*
X121000Y225300D03*
X109400Y225400D03*
X90813D03*
X79800Y225900D03*
X87227Y242891D03*
X87263Y264658D03*
X90652Y265960D03*
X87698Y246708D03*
X94051Y265872D03*
X91230Y247047D03*
X91819Y250396D03*
X94793Y252595D03*
X98211Y252758D03*
X142933Y251431D03*
X132651Y255357D03*
X138228Y260175D03*
X124933Y270414D03*
X136427Y251413D03*
X124874Y273953D03*
X137809Y247647D03*
X135592Y257933D03*
X116566Y254205D03*
X114229Y270684D03*
X119242Y252107D03*
X112042Y275903D03*
X121685Y249741D03*
X121741Y246341D03*
X118219Y274497D03*
X122572Y258147D03*
X121599Y274869D03*
X130567Y258051D03*
X113558Y261260D03*
X111008Y242830D03*
X106381Y259865D03*
X106504Y243329D03*
X103610Y268626D03*
X102713Y242975D03*
X103003Y260260D03*
X108652Y247260D03*
X107887Y266647D03*
X101242Y265901D03*
X100415Y246679D03*
X126611Y258265D03*
X84863Y229783D03*
X134529Y264470D03*
X137190Y266587D03*
X131901Y267444D03*
X132163Y271041D03*
X137690Y273752D03*
X110610Y206436D03*
X125600Y221200D03*
X113863Y228669D03*
X102559Y228575D03*
X97885Y228339D03*
X147013Y225483D03*
X94600Y206900D03*
X94548Y211258D03*
X109534Y314564D03*
X92682Y331571D03*
X119603Y285731D03*
X124478Y280855D03*
X95202Y290958D03*
X98565Y290455D03*
X102107Y290439D03*
X105603Y291092D03*
X95146Y279609D03*
X110808Y291075D03*
X98546Y279609D03*
X114915Y290203D03*
X104413Y278608D03*
X117027Y278475D03*
X148834Y284832D03*
X107750Y277953D03*
X128918Y307533D03*
X135308Y276806D03*
X139784Y276432D03*
X142241Y278783D03*
X95400Y383083D03*
X84200Y380000D03*
X90878Y585185D03*
X85654Y659044D03*
X83960Y632636D03*
X83500Y653600D03*
Y640044D03*
X84900Y747900D03*
X90746Y712435D03*
X90947Y709040D03*
X91003Y705214D03*
X91130Y701741D03*
X85300Y755100D03*
X85000Y775900D03*
X84100Y769000D03*
X220131Y58163D03*
X197900Y82000D03*
X201237Y106350D03*
X210356Y99104D03*
X210680Y84396D03*
X201614Y89932D03*
X212028Y93512D03*
X212800Y125800D03*
X182400Y128300D03*
X175598Y128436D03*
X220100Y123600D03*
X166700Y128800D03*
X172200Y128300D03*
X179000D03*
X152350Y131084D03*
X204849Y106438D03*
X200100Y101200D03*
X170302Y147100D03*
X158100Y166800D03*
X160311Y141680D03*
X219548Y174651D03*
X208200Y153500D03*
X203900D03*
X200100Y146500D03*
Y150400D03*
X199100Y153800D03*
X194800D03*
X174339Y151172D03*
X178400Y152300D03*
X167015Y167633D03*
X163550Y179657D03*
X172645Y179104D03*
X177087Y178920D03*
X183120Y266103D03*
X183082Y271969D03*
X182853Y256107D03*
X183956Y261452D03*
X168010Y267909D03*
X219717Y211198D03*
X182177Y251208D03*
X154300Y227900D03*
X171200Y233000D03*
X185563Y245456D03*
X175064Y232857D03*
X185740Y240983D03*
X185502Y237383D03*
X152663Y272053D03*
X192284Y258847D03*
X150666Y243134D03*
X195698Y259749D03*
X196365Y256414D03*
X168324Y246397D03*
X171762Y258345D03*
X167894Y243024D03*
X167760Y239626D03*
X156800Y230500D03*
X216335Y218212D03*
X180641Y231683D03*
X183043Y276658D03*
X183707Y289861D03*
X183653Y283162D03*
X185042Y286734D03*
X167051Y293752D03*
X188273Y285674D03*
X187118Y281963D03*
X163142Y294193D03*
X172818Y288683D03*
X177715Y397471D03*
X212500Y395500D03*
X217800Y395900D03*
X200161Y416474D03*
X206142Y413945D03*
X206871Y397177D03*
X210042Y412265D03*
X173864Y397677D03*
X213400Y434601D03*
X210772Y431456D03*
X200453Y439066D03*
X203186Y451492D03*
X180445Y422567D03*
X176991Y463723D03*
X184750Y427953D03*
X208947Y443700D03*
X196803Y444462D03*
X201400Y434400D03*
X202764Y444274D03*
X190887Y424438D03*
X174500Y424100D03*
X182060Y443776D03*
X211243Y462005D03*
X203406Y454885D03*
X195038Y477148D03*
X180313Y446694D03*
X176915Y446556D03*
X195400Y452051D03*
X208632Y457048D03*
X181034Y427967D03*
X177700Y427300D03*
X210223Y501477D03*
X213500Y503600D03*
X216300Y499600D03*
X193016Y496643D03*
X219492Y517832D03*
X219590Y740816D03*
X254498Y88487D03*
X251687Y98033D03*
X261830Y81230D03*
X241101D03*
X256928Y69301D03*
X241132Y85023D03*
X259815Y94233D03*
X242488Y88466D03*
X223948Y174292D03*
X251700Y135484D03*
X231350Y222067D03*
X238614Y217763D03*
X222496Y222320D03*
X223129Y210901D03*
X224664Y293860D03*
X257400Y403206D03*
X239600Y405600D03*
X237800Y411200D03*
X226576Y401835D03*
X222269Y402278D03*
X228949Y410741D03*
X225421Y410908D03*
X269840Y386256D03*
X239693Y396029D03*
X257500Y399300D03*
X264600Y380500D03*
X270800Y408500D03*
X261300Y402355D03*
X275500Y415400D03*
X264124Y408219D03*
X258267Y408800D03*
X233400Y409700D03*
X255010Y367624D03*
X273554Y386722D03*
X223600Y456200D03*
X246502Y472752D03*
X255622Y461532D03*
X263000Y438800D03*
X260600Y435900D03*
X258299Y432800D03*
X250400Y440000D03*
X249600Y428100D03*
X237700Y458000D03*
X269300Y486200D03*
X249600Y432500D03*
X239000Y440300D03*
X244800Y454500D03*
X229600Y460700D03*
X289200Y445100D03*
X252200Y486700D03*
X290300Y462400D03*
X290011Y456234D03*
X289000Y449200D03*
X221035Y453935D03*
X279120Y440440D03*
X276761Y443421D03*
X277575Y449398D03*
X270714Y458323D03*
X263719Y455536D03*
X259779Y456823D03*
X220768Y418393D03*
X260322Y462288D03*
X256852Y465331D03*
X258221Y469246D03*
X235069Y464940D03*
X257184Y421241D03*
X271342Y440630D03*
X235600Y433300D03*
X264775Y459236D03*
X279789Y432846D03*
X285565Y438912D03*
X250400Y473300D03*
X260481Y473769D03*
X253214Y469048D03*
X228400Y486400D03*
X228001Y474064D03*
X226000Y458700D03*
X249845Y469508D03*
X229300Y442500D03*
X225700Y496800D03*
X226115Y507011D03*
X229513Y507141D03*
X232912Y507242D03*
X283657Y532832D03*
X280259Y532714D03*
X232200Y492100D03*
X231739Y495469D03*
X248286Y489208D03*
X242100Y489000D03*
X268600Y529800D03*
X256300Y531400D03*
X289400Y511700D03*
X243300Y527900D03*
X247256Y529218D03*
X251700Y531500D03*
X268500Y525800D03*
X238118Y492166D03*
X246132Y492160D03*
X289405Y515437D03*
X228500Y498900D03*
X281183Y592936D03*
X223671Y740896D03*
X223129Y764830D03*
X271970Y798668D03*
X282413Y798410D03*
X228021Y787335D03*
X223596Y782163D03*
X236973Y795418D03*
X235169Y791455D03*
X240130Y789012D03*
X314000Y405200D03*
X316800Y415900D03*
X299800Y398500D03*
X332600Y400100D03*
X304783Y467192D03*
X295115Y476433D03*
Y473033D03*
X297715Y479588D03*
X306603Y459523D03*
X301437Y426833D03*
X304200Y432600D03*
X300603Y432406D03*
X309200Y444700D03*
X331800Y440400D03*
X331900Y444600D03*
X356700Y437500D03*
X348800D03*
X341500Y437400D03*
X291300Y468600D03*
X308900Y449100D03*
X327900Y438100D03*
X341430Y459351D03*
X345735Y460843D03*
X349800Y460000D03*
X353698Y460323D03*
X357812Y460406D03*
X297238Y429641D03*
X304550Y424222D03*
X300059Y422844D03*
X304000Y538500D03*
X308800Y540925D03*
X350400Y512000D03*
X335600Y511400D03*
X304700Y509500D03*
X317900Y520100D03*
X314628Y517729D03*
X343905Y519116D03*
X324400Y570500D03*
X346510Y796385D03*
X350765D03*
X315696Y798445D03*
X294148Y798547D03*
X305437Y798205D03*
X362793Y77815D03*
Y126096D03*
X381025Y73748D03*
Y120650D03*
X373496Y140021D03*
X365131Y135484D03*
X413900Y396400D03*
X428343Y463067D03*
X420575Y467336D03*
X382695Y467033D03*
Y471133D03*
X388884Y468631D03*
X387143Y462647D03*
X378700Y437600D03*
X371200Y437800D03*
X363800Y437700D03*
X361533Y460222D03*
X365241Y460010D03*
X416588Y467839D03*
X361814Y796557D03*
X500295Y401715D03*
X501800Y387600D03*
X473838Y385675D03*
X474106Y382285D03*
X473605Y389068D03*
X499764Y411324D03*
X497279Y382551D03*
X435138Y460661D03*
X457091Y486699D03*
X452300Y420900D03*
X483100Y449900D03*
X501700Y477200D03*
X483530Y541762D03*
X487073Y554094D03*
X482183Y535169D03*
X483008Y500529D03*
X469932Y518034D03*
X447307Y511890D03*
X447090Y497242D03*
X471410Y490049D03*
X498994Y488322D03*
X501802Y490240D03*
X523200Y399400D03*
X506100Y380000D03*
X517041Y388700D03*
X536928Y411324D03*
X514000Y486293D03*
X508306Y428179D03*
X504500Y479500D03*
X514073Y552477D03*
X503300Y539700D03*
X637200Y393900D03*
X629100Y536000D03*
X632600Y555200D03*
X636200Y555100D03*
X640100Y550600D03*
X662100Y394600D03*
X667979Y486293D03*
X702400Y431500D03*
X698300Y431600D03*
X702000Y485700D03*
X688615Y485133D03*
X707700Y476500D03*
X707890Y467821D03*
X684259Y476130D03*
X682774Y449737D03*
X667745Y456089D03*
X662604Y463284D03*
X671915Y543133D03*
X694700Y547700D03*
X688800Y540450D03*
X702400Y554800D03*
X705927Y538650D03*
X663600Y535395D03*
X644600Y556700D03*
X652400Y545200D03*
X674375Y509826D03*
X700512Y510204D03*
X643833Y549325D03*
X702000Y546581D03*
X702400Y550600D03*
X684600Y542100D03*
X682015Y493633D03*
X669200Y559600D03*
X656817Y567131D03*
X697600Y560000D03*
X701400Y560200D03*
X643100Y589900D03*
X689945Y758289D03*
X700989Y759255D03*
X667982Y739870D03*
X681402Y757754D03*
X663575Y742289D03*
X668987Y731465D03*
X691075Y820814D03*
X711116Y796516D03*
X702290Y820921D03*
X680480Y773302D03*
X678755Y784815D03*
X676727Y790555D03*
X679630Y795856D03*
X680239Y802378D03*
X682693Y806283D03*
X684732Y810518D03*
X669886Y786112D03*
X666516Y784722D03*
X686308Y834802D03*
X646342Y826469D03*
X685799Y770894D03*
X690211Y827401D03*
X683715Y852233D03*
X710727Y862002D03*
X678351Y854383D03*
X679332Y841866D03*
X681156Y844982D03*
X681542Y848361D03*
X722687Y120650D03*
X727300Y273200D03*
X758200Y338900D03*
X756700Y370600D03*
X762900Y387400D03*
X729700Y551500D03*
X729600Y540400D03*
X724000Y532600D03*
X722682Y538700D03*
X716300Y517125D03*
X719800Y525000D03*
X719866Y528656D03*
X751965Y522097D03*
X747886D03*
X757848Y513543D03*
X752874Y534854D03*
X737297Y517903D03*
X756523Y520272D03*
X749493Y535216D03*
X725100Y519600D03*
X746000Y549700D03*
X726800Y527400D03*
X723538Y526440D03*
X742607Y549481D03*
X752100Y506500D03*
X749500Y508800D03*
X742000Y505000D03*
X762275Y512870D03*
X744073Y522097D03*
X755862Y516303D03*
X756400Y508100D03*
X756272Y534995D03*
X763000Y490800D03*
X717879Y564572D03*
X737400Y576200D03*
X766358Y564600D03*
X727700Y584400D03*
X758400Y568500D03*
X742600Y577100D03*
X756100Y658700D03*
X757600Y639700D03*
X746669Y740179D03*
X743653Y744114D03*
X741453Y748054D03*
X738850Y751989D03*
X734450Y755929D03*
X730967Y759864D03*
X724305Y770450D03*
X723678Y774016D03*
X727477Y775212D03*
X724733Y779559D03*
X730028Y782297D03*
X724859Y784497D03*
X742663Y788885D03*
X729988Y787114D03*
X739510Y795264D03*
X725239Y788970D03*
X745230Y793211D03*
X729486Y791416D03*
X742370Y799077D03*
X725407Y794540D03*
X747659Y796960D03*
X744790Y802781D03*
X749593Y803991D03*
X747556Y808994D03*
X749629Y812608D03*
X722443Y826463D03*
X721704Y829981D03*
X724858Y831254D03*
X723801Y834857D03*
X726332Y837128D03*
X733066Y836450D03*
X729250Y850000D03*
X721243Y850725D03*
X718263Y863827D03*
X745100Y859405D03*
X721112Y854419D03*
X724093Y840187D03*
X726776Y842277D03*
X733796Y854172D03*
G54D17*
X22980Y59055D03*
X30854D03*
X22980Y106299D03*
Y98425D03*
Y90551D03*
Y82677D03*
Y74803D03*
Y66929D03*
X30854Y98425D03*
Y90551D03*
Y82677D03*
Y74803D03*
Y66929D03*
X41142Y135669D03*
Y155669D03*
Y145669D03*
X26181Y537559D03*
Y527559D03*
Y517559D03*
X41142Y655669D03*
Y645669D03*
Y635669D03*
Y763780D03*
Y753780D03*
Y773780D03*
G54D20*
X57200Y175300D03*
X39600Y494800D03*
X38200Y490900D03*
X35100Y494400D03*
X209100Y51700D03*
X191700Y63300D03*
X209200Y65100D03*
X200700Y51700D03*
X185100Y55900D03*
X208900Y58600D03*
X192000Y55900D03*
X200700Y58300D03*
X184700Y63100D03*
X209000Y72300D03*
X201500D03*
X177100Y99500D03*
X177200Y104800D03*
X177300Y94200D03*
Y88500D03*
X184700D03*
X190700Y77800D03*
X201200Y65600D03*
X191000Y71300D03*
X184500Y71200D03*
X177400Y71400D03*
X177500Y77900D03*
X183700Y78100D03*
X191500Y88500D03*
X169800Y155796D03*
X165162Y155909D03*
X169709Y160049D03*
X165388Y160094D03*
X228728Y96613D03*
X224285Y96750D03*
X256823Y221979D03*
X352066Y262596D03*
X307320Y223390D03*
X320207Y428442D03*
X320166Y432442D03*
X376144Y279856D03*
X410200Y474200D03*
X410179Y469769D03*
X438300Y481200D03*
X434515Y483333D03*
X434412Y479334D03*
X432014Y476132D03*
X566000Y536700D03*
X633923Y520400D03*
X711500Y438300D03*
X644900Y538300D03*
X678293Y698772D03*
X675736Y657222D03*
X694061Y681726D03*
X697897Y662763D03*
X708231Y730948D03*
X681276Y722211D03*
X698962Y707936D03*
X715795Y697494D03*
X750300Y663000D03*
X740513Y687906D03*
X745733Y713048D03*
X764200Y813000D03*
G54D22*
X54724Y557087D03*
Y620079D03*
Y675197D03*
Y738189D03*
X144843Y798779D03*
Y874449D03*
G54D28*
X276982Y828335D03*
X286982Y818335D03*
X276982D03*
X356982D03*
X346982D03*
X336982D03*
X326982D03*
X316982D03*
X306982D03*
X296982D03*
X366982D03*
G54D21*
X53547Y322486D03*
Y302486D03*
G54D24*
X144843Y812994D03*
Y860234D03*
G54D16*
X6614Y553544D03*
X10551Y623622D03*
X6614Y671654D03*
X10551Y741732D03*
X18425Y553544D03*
X32204D03*
X18425Y623622D03*
X32204D03*
X18425Y671654D03*
X32204D03*
X18425Y741732D03*
X32204D03*
G54D26*
X229764Y513034D03*
X234416Y512963D03*
X238924Y512390D03*
X243100Y516300D03*
X245963Y511890D03*
X250975Y511729D03*
X255500Y514000D03*
X264000Y513400D03*
X414894Y453432D03*
X419296Y449111D03*
X423572Y453454D03*
X419092Y457572D03*
X419225Y453324D03*
X428616Y429466D03*
X391500Y459000D03*
X399900Y458600D03*
X421273Y439381D03*
X475600Y462100D03*
X458900Y446600D03*
X488500Y474200D03*
X450300Y459900D03*
X471300Y482200D03*
X449000Y480000D03*
X438316Y449493D03*
X438294Y453811D03*
G54D11*
X-138100Y222300D03*
Y241300D03*
Y260300D03*
Y279300D03*
Y298300D03*
Y317300D03*
Y336300D03*
X-70100Y222300D03*
X-87100D03*
X-104100D03*
X-121100D03*
X-70100Y241300D03*
X-87100D03*
X-104100D03*
X-121100D03*
X-70100Y260300D03*
X-87100D03*
X-104100D03*
X-121100D03*
X-70100Y279300D03*
X-87100D03*
X-104100D03*
X-121100D03*
X-70100Y298300D03*
X-87100D03*
X-104100D03*
X-121100D03*
X-70100Y317300D03*
X-87100D03*
X-104100D03*
X-121100D03*
X-70100Y336300D03*
X-87100D03*
X-104100D03*
X-121100D03*
X4800Y48600D03*
X5800Y6400D03*
X5000Y71900D03*
Y91900D03*
X5100Y111800D03*
X4900Y130400D03*
X5000Y150500D03*
X5300Y170000D03*
X-2100Y222300D03*
X-19100D03*
X-36100D03*
X-53100D03*
X-2100Y241300D03*
X-19100D03*
X-36100D03*
X-53100D03*
X-2100Y260300D03*
X-19100D03*
X-36300Y260000D03*
X-53100Y260300D03*
X-1900Y288300D03*
X-49400Y284500D03*
X-19600Y279500D03*
X-36100Y279300D03*
X-2100Y298300D03*
X-19100D03*
X-36100D03*
X-53100D03*
X-2100Y317300D03*
X-19100D03*
X-36100D03*
X-53100D03*
X-2100Y336300D03*
X-19100D03*
X-36100D03*
X-53100D03*
X-1600Y413600D03*
Y394600D03*
Y375600D03*
Y356600D03*
X-52600Y413600D03*
X-35600D03*
X-18600D03*
X-52600Y394600D03*
X-35600D03*
X-18600D03*
X-52600Y375600D03*
X-35600D03*
X-18600D03*
X-52600Y356600D03*
X-35600D03*
X-18600D03*
X-19400Y483400D03*
X-2400D03*
X-36400D03*
X-53400D03*
X-1500Y470300D03*
Y451300D03*
Y432300D03*
X-52500Y470300D03*
X-35500D03*
X-18500D03*
X-52500Y451300D03*
X-35500D03*
X-18500D03*
X-52500Y432300D03*
X-35500D03*
X-18500D03*
X9151Y473051D03*
X8672Y487593D03*
X-19400Y502400D03*
X-2400D03*
X-36400D03*
X-53400D03*
X7075Y527972D03*
X7927Y509647D03*
X8140Y637282D03*
X8246Y771416D03*
X45700Y61000D03*
X65500Y60800D03*
X75500D03*
X45900Y50000D03*
X65700Y49800D03*
X50800Y39500D03*
X70700Y45800D03*
X55800Y61300D03*
X59900Y40600D03*
X53200Y26300D03*
X50600Y6000D03*
X50500Y67700D03*
X70500Y72000D03*
X60800Y72500D03*
X73700Y199700D03*
X69000Y202700D03*
X77200Y189000D03*
X72001Y265901D03*
X69400Y207400D03*
X54515Y396433D03*
X54463Y386651D03*
X43569Y379314D03*
X16158Y477255D03*
X20715Y485712D03*
X20276Y477090D03*
X51383Y514037D03*
X63862Y512438D03*
X73542Y514340D03*
X37200Y513500D03*
X33600Y512600D03*
X37329Y524472D03*
X33880Y526500D03*
X33921Y520414D03*
X18809Y491871D03*
X17212Y532250D03*
X18064Y513925D03*
X56121Y494271D03*
X21090Y497108D03*
X66300Y548000D03*
X69569Y594959D03*
X69520Y560987D03*
X68421Y570392D03*
X69323Y579887D03*
X69518Y604727D03*
X69220Y614992D03*
X18277Y641560D03*
X9844Y658803D03*
X19981Y663081D03*
X68928Y687846D03*
X69316Y697605D03*
X69911Y676938D03*
X73900Y664900D03*
X77000Y646200D03*
X72930Y645818D03*
X67257Y643668D03*
X9631Y753837D03*
X19768Y758115D03*
X69558Y711913D03*
X68620Y722610D03*
X69217Y732676D03*
X73325Y760926D03*
X67809Y758190D03*
X18383Y775694D03*
X55459Y780063D03*
X48300Y775300D03*
X73282Y778907D03*
X87900Y47800D03*
X90900Y42400D03*
X80400Y47800D03*
X124100Y6700D03*
X110800Y48800D03*
X120200Y48400D03*
X98700Y48900D03*
X143900Y38000D03*
X108100Y35300D03*
X146900Y48500D03*
X109700Y6400D03*
X119700Y35400D03*
X139800Y31100D03*
X96300Y6100D03*
X147200Y7300D03*
X108600Y19900D03*
X126500Y20100D03*
X147500Y90200D03*
X142167Y106366D03*
X142101Y98650D03*
X111100Y75500D03*
X100000Y75600D03*
X121700Y75300D03*
X85300Y70200D03*
X126300Y180209D03*
X126700Y173500D03*
X136291Y179968D03*
X136100Y173800D03*
X84641Y204036D03*
X122100Y203300D03*
X96900Y189286D03*
X134200Y217300D03*
X130000Y217200D03*
X134600Y222200D03*
X122000Y207300D03*
X140103Y328216D03*
X117460Y335158D03*
X128964Y339470D03*
X148102Y338366D03*
X106419Y310245D03*
X126184Y310860D03*
X93200Y308800D03*
X121477Y314973D03*
X135613Y308903D03*
X114175Y406224D03*
X126063Y406183D03*
X141738Y406224D03*
X106301D03*
X117951Y437592D03*
X114175Y445598D03*
X110263Y441683D03*
X118189Y445711D03*
X125990Y445598D03*
X110238Y437720D03*
X125990D03*
X106341Y426062D03*
X102227Y473344D03*
X145675Y469220D03*
X90376Y476918D03*
X110238Y477094D03*
X141738D03*
X137801Y473157D03*
X98427Y469046D03*
X106301Y469220D03*
X114175D03*
X126057Y469287D03*
X129927Y469220D03*
X137801D03*
X122053Y465283D03*
X133864D03*
X106301Y461346D03*
X122113Y457535D03*
X129963Y461283D03*
X110263Y457283D03*
X122158Y453388D03*
X125990Y477094D03*
X137801Y449535D03*
X118744Y525279D03*
X140399Y525238D03*
X129199Y525271D03*
X107103Y525057D03*
X95599Y525026D03*
X84799Y524898D03*
X118004Y488825D03*
X133864Y488905D03*
X149612D03*
X102308Y488978D03*
X86616Y488905D03*
X91852Y563129D03*
X91156Y572112D03*
X90823Y581387D03*
X91343Y598284D03*
X91023Y606587D03*
X90923Y616187D03*
X90681Y690157D03*
X90174Y678675D03*
X85600Y647837D03*
X106051Y767209D03*
X93840Y699686D03*
X90814Y734451D03*
X91027Y724985D03*
X91094Y715818D03*
X84703Y758885D03*
X84182Y764879D03*
X122899Y825236D03*
X112762Y820958D03*
X116188Y771487D03*
X131900Y893200D03*
X120874Y857517D03*
X110737Y853239D03*
X131700Y915700D03*
X89871Y917500D03*
X173200Y10900D03*
X213700Y35200D03*
X186000D03*
X197796Y12653D03*
X160600Y49100D03*
X153200Y48700D03*
X167500Y49000D03*
X160500Y19700D03*
X170400Y31100D03*
X150600Y37800D03*
X154500Y90000D03*
X158000Y79600D03*
X165200Y79500D03*
X163300Y95900D03*
X163500Y105500D03*
X151800Y72400D03*
X204200Y126700D03*
X206600Y130300D03*
X201900D03*
X205628Y89404D03*
X189600Y166700D03*
X189700Y170200D03*
X190018Y173586D03*
X188961Y162715D03*
X211700Y181600D03*
X207495Y192761D03*
X152663Y267791D03*
X196344Y237383D03*
X196078Y248183D03*
X196021Y244556D03*
X196151Y240983D03*
X151519Y250193D03*
X186319Y268076D03*
X184188Y340638D03*
X162135Y332650D03*
X183466Y294017D03*
X152580Y285530D03*
X216178Y411331D03*
X219144Y414536D03*
X195307Y355649D03*
X206775Y348954D03*
X214660Y362600D03*
X173508Y348462D03*
X175767Y380311D03*
X189073Y380379D03*
X185276Y380362D03*
X181242Y380481D03*
X197565Y380257D03*
X203379Y380312D03*
X169600Y380500D03*
X181980Y458681D03*
X153549Y473157D03*
X184399Y525203D03*
X195499D03*
X206699D03*
X217899Y525103D03*
X162615Y525220D03*
X173537D03*
X151684Y525258D03*
X196400Y585300D03*
X179000Y624800D03*
X193600Y702400D03*
X179100Y714600D03*
X202300Y742000D03*
X157422Y825918D03*
X158725Y835536D03*
X181642Y837321D03*
Y827853D03*
X181772Y818429D03*
X159926Y813000D03*
X201663Y827680D03*
X201142Y837191D03*
X189273Y902478D03*
X213138Y905780D03*
X218729Y857629D03*
X160735Y857183D03*
X154730Y847010D03*
X181081Y856307D03*
X181124Y847013D03*
X200798Y846849D03*
X200460Y913771D03*
X282282Y47189D03*
X286930D03*
X233900Y32500D03*
X266700Y46900D03*
X263000Y47000D03*
X257500Y46900D03*
X253800Y47000D03*
X244900Y47300D03*
X248600Y47200D03*
X252187Y23895D03*
X286651Y14571D03*
X224431Y15210D03*
X248900Y8400D03*
X235000Y47500D03*
X238700Y47400D03*
X225231Y58420D03*
X282444Y106834D03*
X225919Y88394D03*
X225937Y80731D03*
X221710Y80767D03*
X221722Y88431D03*
X230158Y88359D03*
X230123Y80805D03*
X225851Y73774D03*
X221740Y73844D03*
X229870Y73970D03*
X228169Y68374D03*
X224169Y68520D03*
X248000Y114500D03*
X246100Y151300D03*
Y155800D03*
Y160400D03*
X258741Y193852D03*
X231049Y188760D03*
X246169Y246270D03*
X230774Y270268D03*
X241694Y274956D03*
X228243Y380358D03*
X228635Y385956D03*
X232788Y385893D03*
X231915Y380533D03*
X244928Y367685D03*
X238151Y356092D03*
X228510Y367624D03*
X240715Y380333D03*
X224515Y532633D03*
X237336Y531828D03*
X236700Y539300D03*
X240400Y534500D03*
X245800D03*
X241300Y539300D03*
X236300Y535600D03*
X243200Y531700D03*
X288586Y493703D03*
X268215Y490733D03*
X251755Y491731D03*
X270700Y495400D03*
X274315Y497133D03*
X277300Y572500D03*
X259600Y568400D03*
X271949Y648699D03*
X272588Y681087D03*
X244248Y682153D03*
X255542Y665532D03*
X241904Y652321D03*
X289634Y659352D03*
X284520Y743307D03*
X282176Y713475D03*
X228249Y761450D03*
X230823Y823850D03*
X237950Y774979D03*
X237815Y779065D03*
X226949Y782735D03*
X253623Y867319D03*
X254262Y899707D03*
X225922Y900773D03*
X237216Y884152D03*
X223578Y870941D03*
X285585Y897363D03*
X283241Y867531D03*
X264212Y903112D03*
X277254Y852624D03*
X299300Y41300D03*
X321300Y43200D03*
X351800Y42200D03*
X360500Y42600D03*
X330000Y42800D03*
X329900Y37100D03*
X321300D03*
X360500Y36700D03*
X291373Y47394D03*
X299300Y46400D03*
X351800Y36300D03*
X299600Y62100D03*
X351900Y62000D03*
X360200Y62300D03*
X329500Y62600D03*
X321300Y63100D03*
X325006Y15636D03*
X299500Y68200D03*
X352000Y68000D03*
X360200Y68200D03*
X329600D03*
X321400Y68500D03*
X344663Y108965D03*
X312275Y98098D03*
X354197Y158187D03*
X301140Y161383D03*
X301781Y258122D03*
X322022Y279856D03*
X305456Y481787D03*
X335532Y485626D03*
X323215Y485633D03*
X318015Y493833D03*
X334315Y496733D03*
X330815Y493433D03*
X327115Y489533D03*
X344815Y494933D03*
X321415Y497133D03*
X309648Y582024D03*
X319679Y655730D03*
X320318Y688118D03*
X291978Y689184D03*
X303272Y672563D03*
X347378Y688332D03*
X358672Y671711D03*
X345034Y658500D03*
X302115Y693462D03*
X360803Y704312D03*
X333102Y737766D03*
X344396Y721145D03*
X330758Y707934D03*
X312221Y709853D03*
X312860Y742241D03*
X295814Y726686D03*
X319171Y767846D03*
X313959Y724732D03*
X354623Y896937D03*
X352279Y867105D03*
X313286Y863909D03*
X313925Y896297D03*
X296879Y880742D03*
X332436Y858576D03*
X337648Y901690D03*
X382100Y61900D03*
X401343Y58465D03*
X394098Y20059D03*
X362775D03*
X412506Y33484D03*
X382200Y68500D03*
X410025Y87658D03*
X390208Y180135D03*
X366982Y198886D03*
X407769Y204757D03*
X384668Y247681D03*
X380956Y408290D03*
X376513Y408085D03*
X371865D03*
X380392Y416962D03*
X375949Y416757D03*
X371301D03*
X366653Y416484D03*
X367217Y407812D03*
X366719Y424200D03*
X371367Y424473D03*
X376015D03*
X380458Y424678D03*
X375079Y654878D03*
X375718Y687266D03*
X430267Y679595D03*
X413860Y696428D03*
X400222Y683217D03*
X388817Y692040D03*
X420252Y725194D03*
X420891Y757582D03*
X392551Y758648D03*
X403845Y742027D03*
X390207Y728816D03*
X361442Y736700D03*
X430906Y711983D03*
X402566Y713049D03*
X395450Y767846D03*
X378868Y723311D03*
X421530Y814262D03*
X419186Y784430D03*
X429202Y894806D03*
X426858Y864974D03*
X382324Y863483D03*
X382963Y895871D03*
X365917Y880316D03*
X413927Y901690D03*
X397345Y857155D03*
X432682Y23909D03*
X472315Y23056D03*
X496393Y55871D03*
X457399Y46069D03*
X496109Y93412D03*
X457989Y78967D03*
X493200Y145500D03*
X451789Y154565D03*
X473097Y208901D03*
X453252Y250240D03*
X500526Y394177D03*
X494400Y493600D03*
Y497500D03*
X455846Y546626D03*
X471650Y493916D03*
X494410Y501344D03*
X458713Y518034D03*
X482200Y529100D03*
X484200Y538000D03*
X483800Y545700D03*
X452652Y495705D03*
X465900Y501200D03*
X465212Y726260D03*
X465851Y758648D03*
X437511Y759714D03*
X448805Y743093D03*
X435167Y729882D03*
X474587Y765253D03*
X445197Y719047D03*
X449231Y780808D03*
X449870Y813196D03*
X432824Y797641D03*
X476931Y795085D03*
X488225Y778464D03*
X499945Y828325D03*
X486307Y815114D03*
X456903Y861352D03*
X457542Y893740D03*
X440496Y878185D03*
X488651Y844946D03*
X499208Y899795D03*
X463674Y852891D03*
X557547Y24335D03*
X526213Y34431D03*
X555558Y100229D03*
X531425Y77545D03*
X545330Y147959D03*
X521476Y205704D03*
X509632Y174434D03*
X526688Y248818D03*
X513500Y399060D03*
X520900Y388100D03*
X523462Y423957D03*
X503923Y423910D03*
X536736Y418540D03*
X529000Y550500D03*
X502318Y535328D03*
X521002Y555911D03*
X525300Y552800D03*
X516900Y561200D03*
X528000Y562900D03*
X512700Y560000D03*
X508224Y580873D03*
X549379Y653173D03*
X504632Y761631D03*
X505271Y794019D03*
X516352Y811492D03*
X562377Y833013D03*
X532332Y836635D03*
X516991Y843880D03*
X563016Y865401D03*
X534676Y866467D03*
X545970Y849846D03*
X545118Y880530D03*
X528711Y897363D03*
X515073Y884152D03*
X562590Y881808D03*
X510579Y854786D03*
X545757Y912918D03*
X517417Y913984D03*
X564934Y911640D03*
X573457Y59531D03*
X621826Y20111D03*
X591122Y33010D03*
X607704Y77545D03*
X586385Y204283D03*
X596334Y173012D03*
X602967Y248818D03*
X638300Y511800D03*
X641800Y519000D03*
X639500Y521900D03*
X641700Y510300D03*
X587942Y582024D03*
X614582Y653599D03*
X604141Y675547D03*
X578784Y682152D03*
X582620Y653386D03*
X632693Y697281D03*
X607550Y703460D03*
X628006Y720720D03*
X592635Y878186D03*
X576228Y895019D03*
X640791Y876268D03*
X641430Y908656D03*
X613090Y909722D03*
X624384Y893101D03*
X610746Y879890D03*
X593274Y910574D03*
X660180Y56547D03*
X657451Y28746D03*
X703700Y30300D03*
X651658Y95968D03*
X692985Y75650D03*
X699619Y201914D03*
X652714Y200019D03*
X692512Y162589D03*
X661673Y260892D03*
X688248Y246923D03*
X712386Y297542D03*
X693509Y431701D03*
X689111Y431612D03*
X684869Y431611D03*
X680738Y431633D03*
X651000Y467700D03*
X646163Y482677D03*
X643296Y477617D03*
X643914Y470592D03*
X648652Y470028D03*
X654990Y463513D03*
X658399Y460842D03*
X659485Y455066D03*
X666818Y452921D03*
X694995Y453626D03*
X694923Y461253D03*
X694851Y469456D03*
X694907Y476993D03*
X710645Y447266D03*
X678767Y447136D03*
X672583Y467901D03*
X667831Y479556D03*
X711409Y467621D03*
X665499Y556600D03*
X651800Y540295D03*
X711400Y515400D03*
X711900Y521500D03*
X675400Y538100D03*
X662200Y547300D03*
X709600Y524100D03*
X668135Y523360D03*
X672161Y528021D03*
X676550Y523677D03*
X672342Y519560D03*
X672257Y523769D03*
X658314Y526697D03*
X672168Y538889D03*
X676115Y542633D03*
X685815Y496140D03*
X689996Y496274D03*
X694169Y496394D03*
X698475Y496387D03*
X702670Y496148D03*
X707296Y496348D03*
X712102Y542133D03*
X707589Y515400D03*
X700900Y539500D03*
X707391Y564566D03*
X654641Y691101D03*
X643987Y664041D03*
X650805Y716671D03*
X692356Y875629D03*
X692995Y908017D03*
X664655Y909083D03*
X675949Y892462D03*
X662311Y879251D03*
X754800Y56800D03*
Y36800D03*
Y16800D03*
X723466Y60810D03*
X721334Y17767D03*
X754800Y76800D03*
X754700Y117600D03*
Y97600D03*
X734333Y88085D03*
X754700Y197600D03*
Y177600D03*
Y157600D03*
Y137600D03*
Y257600D03*
Y237600D03*
Y217600D03*
Y277600D03*
X753800Y303200D03*
X767300Y340400D03*
X766900Y333754D03*
X735134Y289819D03*
X767000Y410900D03*
X766700Y403500D03*
X766900Y395400D03*
Y387800D03*
Y364600D03*
Y356300D03*
X767600Y348500D03*
X716700Y445400D03*
X742200Y472500D03*
X724300Y454000D03*
X719100Y478900D03*
X767400Y481600D03*
Y465900D03*
X767500Y450800D03*
X767300Y441747D03*
X766500Y435100D03*
X766800Y427000D03*
X767100Y418700D03*
X744986Y481255D03*
X749974Y477780D03*
X749628Y471196D03*
X739751Y469686D03*
X735295Y463720D03*
X738636Y457903D03*
X731780Y452531D03*
X729478Y459116D03*
X721600Y451000D03*
X719700Y485600D03*
X768000Y457700D03*
X767700Y473300D03*
X767100Y544600D03*
X766800Y535700D03*
X767200Y524500D03*
X766900Y497700D03*
X767200Y489700D03*
X767100Y623900D03*
Y614800D03*
X766700Y606900D03*
X767700Y600200D03*
X766700Y592700D03*
X767000Y584300D03*
Y576100D03*
Y569500D03*
X725900Y561800D03*
X726000Y650700D03*
X720000Y650800D03*
X733000Y650600D03*
X740000D03*
X766900Y639500D03*
Y631900D03*
X745413Y854763D03*
X716221Y876694D03*
X729859Y889905D03*
X718565Y906526D03*
X746905Y905460D03*
X746266Y873072D03*
G54D18*
X29528Y19685D03*
X76772D03*
X108268Y905512D03*
X155512D03*
G54D25*
X182681Y580832D03*
Y560832D03*
G54D13*
X-33503Y269685D03*
G54D29*
X716535Y39370D03*
G54D10*
X-1011811Y-15748D03*
Y940945D03*
X775591Y-15748D03*
Y940944D03*
G54D12*
X-59094Y277559D03*
X-7913D03*
G54D19*
X30854Y106299D03*
G54D27*
X286982Y828335D03*
X356982D03*
X346982D03*
X336982D03*
X326982D03*
X316982D03*
X306982D03*
X296982D03*
X366982D03*
G54D23*
X109410Y796831D03*
Y876397D03*
X168465Y796831D03*
Y876397D03*
%LPC*%
G75*
G54D30*
G01X-771361Y-182763D02*
Y-262763D01*
G01Y-218263D02*
X373639D01*
G01X-771361Y-262763D02*
X373639D01*
G01X-775361Y-166763D02*
G02I-12000J0D01*
G01X-780511D02*
G02I-6850J0D01*
G01X-787361Y-182763D02*
Y-150763D01*
G01X-771361Y-166763D02*
X-803361D01*
G01X-771361Y-182763D02*
X373639D01*
G01X-413861D02*
Y-262763D01*
G01X-276361Y-182763D02*
Y-262763D01*
G01X-161361Y-182763D02*
Y-262763D01*
G01X6139Y-182763D02*
Y-262763D01*
G01X176139Y-182763D02*
Y-262763D01*
G01X373639Y-182763D02*
Y-262763D01*
G01X401639Y-166763D02*
G02I-12000J0D01*
G01X396489D02*
G02I-6850J0D01*
G01X389639Y-182763D02*
Y-150763D01*
G01X405639Y-166763D02*
X373639D01*
G54D31*
G01X-755164Y-252763D02*
Y-235263D01*
G01X-746868D02*
X-755164Y-246055D01*
G01X-745558Y-252763D02*
X-751453Y-241097D01*
G01X-737883Y-252763D02*
Y-235263D01*
X-727839Y-252763D01*
Y-235263D01*
G01X-715361Y-252763D02*
X-717108Y-252471D01*
X-718636Y-251305D01*
X-719946Y-249555D01*
X-720820Y-247513D01*
X-721256Y-245180D01*
Y-242846D01*
X-720820Y-240513D01*
X-719946Y-238471D01*
X-718636Y-236722D01*
X-717108Y-235555D01*
X-715361Y-235263D01*
X-713615Y-235555D01*
X-712086Y-236722D01*
X-710776Y-238471D01*
X-709902Y-240513D01*
X-709466Y-242846D01*
Y-245180D01*
X-709902Y-247513D01*
X-710776Y-249555D01*
X-712086Y-251305D01*
X-713615Y-252471D01*
X-715361Y-252763D01*
G01X-702446D02*
X-693276Y-235263D01*
G01X-702446D02*
X-693276Y-252763D01*
G01X-658494D02*
X-667228D01*
Y-235263D01*
X-658494D01*
G01X-661988Y-243721D02*
X-667228D01*
G01X-649946Y-252763D02*
X-640776Y-235263D01*
G01X-649946D02*
X-640776Y-252763D01*
G01X-632228D02*
Y-235263D01*
X-626988D01*
X-625241Y-236138D01*
X-623931Y-238180D01*
X-623494Y-240513D01*
X-623931Y-242846D01*
X-625023Y-244596D01*
X-626988Y-245472D01*
X-632228D01*
G01X-615820Y-252763D02*
X-610361Y-235263D01*
X-604902Y-252763D01*
G01X-606868Y-246638D02*
X-613855D01*
G01X-597883Y-252763D02*
Y-235263D01*
X-587839Y-252763D01*
Y-235263D01*
G01X-580164Y-252763D02*
Y-235263D01*
X-575798D01*
X-574051Y-236138D01*
X-572741Y-237305D01*
X-571649Y-239054D01*
X-570776Y-241097D01*
X-570558Y-244013D01*
X-570776Y-246930D01*
X-571649Y-248972D01*
X-572741Y-250722D01*
X-574051Y-251888D01*
X-575798Y-252763D01*
X-580164D01*
G01X-553494D02*
X-562228D01*
Y-235263D01*
X-553494D01*
G01X-556988Y-243721D02*
X-562228D01*
G01X-544728Y-252763D02*
Y-235263D01*
X-539269D01*
X-537523Y-236138D01*
X-536431Y-237305D01*
X-535994Y-239638D01*
X-536431Y-241972D01*
X-537741Y-243430D01*
X-539269Y-244305D01*
X-544728D01*
G01X-539269D02*
X-535994Y-252763D01*
G01X-503615Y-243430D02*
X-502741Y-242555D01*
X-502086Y-241097D01*
X-501649Y-239054D01*
X-502086Y-237305D01*
X-502959Y-236138D01*
X-504488Y-235263D01*
X-510383D01*
Y-252763D01*
X-503178D01*
X-501649Y-251597D01*
X-500776Y-249846D01*
X-500339Y-247805D01*
X-500776Y-245763D01*
X-502086Y-244013D01*
X-503615Y-243430D01*
X-510383D01*
G01X-487861Y-252763D02*
X-489608Y-252471D01*
X-491136Y-251305D01*
X-492446Y-249555D01*
X-493320Y-247513D01*
X-493756Y-245180D01*
Y-242846D01*
X-493320Y-240513D01*
X-492446Y-238471D01*
X-491136Y-236722D01*
X-489608Y-235555D01*
X-487861Y-235263D01*
X-486115Y-235555D01*
X-484586Y-236722D01*
X-483276Y-238471D01*
X-482402Y-240513D01*
X-481966Y-242846D01*
Y-245180D01*
X-482402Y-247513D01*
X-483276Y-249555D01*
X-484586Y-251305D01*
X-486115Y-252471D01*
X-487861Y-252763D01*
G01X-475820D02*
X-470361Y-235263D01*
X-464902Y-252763D01*
G01X-466868Y-246638D02*
X-473855D01*
G01X-457228Y-252763D02*
Y-235263D01*
X-451769D01*
X-450023Y-236138D01*
X-448931Y-237305D01*
X-448494Y-239638D01*
X-448931Y-241972D01*
X-450241Y-243430D01*
X-451769Y-244305D01*
X-457228D01*
G01X-451769D02*
X-448494Y-252763D01*
G01X-440164D02*
Y-235263D01*
X-435798D01*
X-434051Y-236138D01*
X-432741Y-237305D01*
X-431649Y-239054D01*
X-430776Y-241097D01*
X-430558Y-244013D01*
X-430776Y-246930D01*
X-431649Y-248972D01*
X-432741Y-250722D01*
X-434051Y-251888D01*
X-435798Y-252763D01*
X-440164D01*
G01X-633538Y-207763D02*
Y-190263D01*
X-627861Y-204846D01*
X-622184Y-190263D01*
Y-207763D01*
G01X-610361D02*
X-611671Y-207471D01*
X-612981Y-206305D01*
X-613855Y-204263D01*
X-614291Y-201930D01*
X-613855Y-199596D01*
X-612981Y-197555D01*
X-611671Y-196388D01*
X-610361Y-196097D01*
X-609051Y-196388D01*
X-607741Y-197555D01*
X-606868Y-199596D01*
X-606649Y-201930D01*
X-606868Y-204263D01*
X-607741Y-206305D01*
X-609051Y-207471D01*
X-610361Y-207763D01*
G01X-588931Y-190263D02*
Y-207763D01*
G01Y-205139D02*
X-589804Y-206597D01*
X-591115Y-207471D01*
X-592643Y-207763D01*
X-594389Y-207180D01*
X-595699Y-205722D01*
X-596573Y-203972D01*
X-596791Y-201930D01*
X-596573Y-199888D01*
X-595699Y-198138D01*
X-594389Y-196680D01*
X-592643Y-196097D01*
X-591115Y-196388D01*
X-590023Y-196972D01*
X-588931Y-198138D01*
G01X-578636Y-199888D02*
X-571649D01*
X-572304Y-197846D01*
X-573396Y-196680D01*
X-574924Y-196097D01*
X-576453Y-196388D01*
X-577763Y-197263D01*
X-578636Y-199305D01*
X-579073Y-201055D01*
Y-202805D01*
X-578636Y-204555D01*
X-577544Y-206305D01*
X-576234Y-207471D01*
X-574706Y-207763D01*
X-573178Y-207180D01*
X-571649Y-205430D01*
G01X-557861Y-207763D02*
Y-190263D01*
G01X-380161Y-252763D02*
Y-235263D01*
X-382781Y-238763D01*
G01Y-252763D02*
X-377541D01*
G01X-366809Y-238180D02*
X-365499Y-236430D01*
X-363971Y-235555D01*
X-362224Y-235263D01*
X-360041Y-235846D01*
X-358513Y-237305D01*
X-358076Y-239054D01*
X-358294Y-240805D01*
X-359168Y-242263D01*
X-363534Y-245180D01*
X-365499Y-247221D01*
X-366809Y-250139D01*
X-367246Y-252763D01*
X-358076D01*
G01X-345161Y-235263D02*
X-346908Y-235846D01*
X-348218Y-237305D01*
X-349091Y-239054D01*
X-349746Y-241388D01*
X-349964Y-244013D01*
X-349746Y-246638D01*
X-349091Y-248972D01*
X-348218Y-250722D01*
X-346908Y-252180D01*
X-345161Y-252763D01*
X-343415Y-252180D01*
X-342104Y-250722D01*
X-341231Y-248972D01*
X-340576Y-246638D01*
X-340358Y-244013D01*
X-340576Y-241388D01*
X-341231Y-239054D01*
X-342104Y-237305D01*
X-343415Y-235846D01*
X-345161Y-235263D01*
G01X-327661D02*
X-329408Y-235846D01*
X-330718Y-237305D01*
X-331591Y-239054D01*
X-332246Y-241388D01*
X-332464Y-244013D01*
X-332246Y-246638D01*
X-331591Y-248972D01*
X-330718Y-250722D01*
X-329408Y-252180D01*
X-327661Y-252763D01*
X-325915Y-252180D01*
X-324604Y-250722D01*
X-323731Y-248972D01*
X-323076Y-246638D01*
X-322858Y-244013D01*
X-323076Y-241388D01*
X-323731Y-239054D01*
X-324604Y-237305D01*
X-325915Y-235846D01*
X-327661Y-235263D01*
G01X-307541Y-252763D02*
Y-235263D01*
X-315620Y-247805D01*
X-304702D01*
G01X-393278Y-207763D02*
Y-190263D01*
X-388038D01*
X-386291Y-191138D01*
X-384981Y-193180D01*
X-384544Y-195513D01*
X-384981Y-197846D01*
X-386073Y-199596D01*
X-388038Y-200472D01*
X-393278D01*
G01X-366608Y-191722D02*
X-367918Y-190846D01*
X-369446Y-190263D01*
X-371193D01*
X-373158Y-191138D01*
X-374686Y-192596D01*
X-375778Y-194347D01*
X-376651Y-197263D01*
X-376870Y-199888D01*
X-376433Y-202513D01*
X-375778Y-204263D01*
X-374468Y-206013D01*
X-372939Y-207180D01*
X-371411Y-207763D01*
X-369883D01*
X-368354Y-207180D01*
X-367044Y-206305D01*
X-365952Y-205139D01*
G01X-352165Y-198430D02*
X-351291Y-197555D01*
X-350636Y-196097D01*
X-350199Y-194054D01*
X-350636Y-192305D01*
X-351509Y-191138D01*
X-353038Y-190263D01*
X-358933D01*
Y-207763D01*
X-351728D01*
X-350199Y-206597D01*
X-349326Y-204846D01*
X-348889Y-202805D01*
X-349326Y-200763D01*
X-350636Y-199013D01*
X-352165Y-198430D01*
X-358933D01*
G01X-342961Y-213596D02*
X-329861D01*
G01X-323933Y-207763D02*
Y-190263D01*
X-313889Y-207763D01*
Y-190263D01*
G01X-301411Y-207763D02*
X-303158Y-207471D01*
X-304686Y-206305D01*
X-305996Y-204555D01*
X-306870Y-202513D01*
X-307306Y-200180D01*
Y-197846D01*
X-306870Y-195513D01*
X-305996Y-193471D01*
X-304686Y-191722D01*
X-303158Y-190555D01*
X-301411Y-190263D01*
X-299665Y-190555D01*
X-298136Y-191722D01*
X-296826Y-193471D01*
X-295952Y-195513D01*
X-295516Y-197846D01*
Y-200180D01*
X-295952Y-202513D01*
X-296826Y-204555D01*
X-298136Y-206305D01*
X-299665Y-207471D01*
X-301411Y-207763D01*
G01X-218861Y-252763D02*
Y-235263D01*
X-221481Y-238763D01*
G01Y-252763D02*
X-216241D01*
G01X-250570Y-190263D02*
X-245111Y-207763D01*
X-239652Y-190263D01*
G01X-223244Y-207763D02*
X-231978D01*
Y-190263D01*
X-223244D01*
G01X-226738Y-198721D02*
X-231978D01*
G01X-214478Y-207763D02*
Y-190263D01*
X-209019D01*
X-207273Y-191138D01*
X-206181Y-192305D01*
X-205744Y-194638D01*
X-206181Y-196972D01*
X-207491Y-198430D01*
X-209019Y-199305D01*
X-214478D01*
G01X-209019D02*
X-205744Y-207763D01*
G01X-192611Y-208346D02*
X-193048Y-208055D01*
Y-207471D01*
X-192611Y-207180D01*
X-192174Y-207471D01*
Y-208055D01*
X-192611Y-208346D01*
G01X-38294Y-235263D02*
Y-252763D01*
X-47028D01*
G01X-55358Y-250139D02*
X-56667Y-251597D01*
X-58196Y-252471D01*
X-60161Y-252763D01*
X-62126Y-252180D01*
X-63654Y-251013D01*
X-64746Y-248972D01*
X-64964Y-246638D01*
X-64528Y-244305D01*
X-63436Y-242846D01*
X-61907Y-241680D01*
X-60379Y-241388D01*
X-58851Y-241680D01*
X-56886Y-242846D01*
X-57541Y-235263D01*
X-63436D01*
G01X-72202D02*
X-77661Y-252763D01*
X-83120Y-235263D01*
G01X-99964Y-236722D02*
X-98654Y-235846D01*
X-97126Y-235263D01*
X-95379D01*
X-93414Y-236138D01*
X-91886Y-237596D01*
X-90794Y-239347D01*
X-89921Y-242263D01*
X-89702Y-244888D01*
X-90139Y-247513D01*
X-90794Y-249263D01*
X-92104Y-251013D01*
X-93633Y-252180D01*
X-95161Y-252763D01*
X-96689D01*
X-98218Y-252180D01*
X-99528Y-251305D01*
X-100620Y-250139D01*
G01X-117464Y-236722D02*
X-116154Y-235846D01*
X-114626Y-235263D01*
X-112879D01*
X-110914Y-236138D01*
X-109386Y-237596D01*
X-108294Y-239347D01*
X-107421Y-242263D01*
X-107202Y-244888D01*
X-107639Y-247513D01*
X-108294Y-249263D01*
X-109604Y-251013D01*
X-111133Y-252180D01*
X-112661Y-252763D01*
X-114189D01*
X-115718Y-252180D01*
X-117028Y-251305D01*
X-118120Y-250139D01*
G01X-125778Y-190263D02*
Y-207763D01*
X-117044D01*
G01X-99981D02*
Y-196097D01*
G01Y-198138D02*
X-100854Y-196972D01*
X-102165Y-196388D01*
X-103693Y-196097D01*
X-105221Y-196680D01*
X-106531Y-197846D01*
X-107405Y-199596D01*
X-107841Y-201930D01*
X-107405Y-204263D01*
X-106531Y-206013D01*
X-105221Y-207180D01*
X-103693Y-207763D01*
X-102165Y-207471D01*
X-100854Y-206597D01*
X-99981Y-205430D01*
G01X-90996Y-213013D02*
X-89686Y-213596D01*
X-87939Y-213013D01*
X-86848Y-211847D01*
X-85974Y-210388D01*
X-84665Y-205722D01*
X-81826Y-196097D01*
G01X-88813D02*
X-84665Y-205722D01*
G01X-72186Y-199888D02*
X-65199D01*
X-65854Y-197846D01*
X-66946Y-196680D01*
X-68474Y-196097D01*
X-70003Y-196388D01*
X-71313Y-197263D01*
X-72186Y-199305D01*
X-72623Y-201055D01*
Y-202805D01*
X-72186Y-204555D01*
X-71094Y-206305D01*
X-69784Y-207471D01*
X-68256Y-207763D01*
X-66728Y-207180D01*
X-65199Y-205430D01*
G01X-54468Y-207763D02*
Y-196097D01*
G01Y-198430D02*
X-53376Y-197263D01*
X-52284Y-196388D01*
X-50756Y-196097D01*
X-49665Y-196388D01*
X-48354Y-197263D01*
G01X-37186Y-205722D02*
X-36094Y-206888D01*
X-34566Y-207763D01*
X-33256D01*
X-31946Y-207180D01*
X-31073Y-206305D01*
X-30636Y-205139D01*
X-30854Y-203388D01*
X-31728Y-202513D01*
X-35658Y-200763D01*
X-36531Y-198721D01*
X-36094Y-197263D01*
X-35221Y-196388D01*
X-33911Y-196097D01*
X-32601Y-196388D01*
X-31291Y-197263D01*
G01X51772Y-235263D02*
Y-252763D01*
X60506D01*
G01X68836Y-235263D02*
Y-247805D01*
X69709Y-250430D01*
X71456Y-252180D01*
X73639Y-252763D01*
X75822Y-252180D01*
X77569Y-250430D01*
X78442Y-247805D01*
Y-235263D01*
G01X95942Y-236722D02*
X94632Y-235846D01*
X93104Y-235263D01*
X91357D01*
X89392Y-236138D01*
X87864Y-237596D01*
X86772Y-239347D01*
X85899Y-242263D01*
X85680Y-244888D01*
X86117Y-247513D01*
X86772Y-249263D01*
X88082Y-251013D01*
X89611Y-252180D01*
X91139Y-252763D01*
X92667D01*
X94196Y-252180D01*
X95506Y-251305D01*
X96598Y-250139D01*
G01X103836Y-252763D02*
Y-235263D01*
G01X112132D02*
X103836Y-246055D01*
G01X113442Y-252763D02*
X107547Y-241097D01*
G01X126139Y-252763D02*
Y-244888D01*
X121772Y-235263D01*
G01X130506D02*
X126139Y-244888D01*
G01X25086Y-207763D02*
Y-190263D01*
X29452D01*
X31199Y-191138D01*
X32509Y-192305D01*
X33601Y-194054D01*
X34474Y-196097D01*
X34692Y-199013D01*
X34474Y-201930D01*
X33601Y-203972D01*
X32509Y-205722D01*
X31199Y-206888D01*
X29452Y-207763D01*
X25086D01*
G01X44114Y-199888D02*
X51101D01*
X50446Y-197846D01*
X49354Y-196680D01*
X47826Y-196097D01*
X46297Y-196388D01*
X44987Y-197263D01*
X44114Y-199305D01*
X43677Y-201055D01*
Y-202805D01*
X44114Y-204555D01*
X45206Y-206305D01*
X46516Y-207471D01*
X48044Y-207763D01*
X49572Y-207180D01*
X51101Y-205430D01*
G01X61614Y-205722D02*
X62706Y-206888D01*
X64234Y-207763D01*
X65544D01*
X66854Y-207180D01*
X67727Y-206305D01*
X68164Y-205139D01*
X67946Y-203388D01*
X67072Y-202513D01*
X63142Y-200763D01*
X62269Y-198721D01*
X62706Y-197263D01*
X63579Y-196388D01*
X64889Y-196097D01*
X66199Y-196388D01*
X67509Y-197263D01*
G01X82389Y-196097D02*
Y-207763D01*
G01Y-191430D02*
X81952Y-191138D01*
Y-190555D01*
X82389Y-190263D01*
X82826Y-190555D01*
Y-191138D01*
X82389Y-191430D01*
G01X96832Y-212138D02*
X98361Y-213305D01*
X100107Y-213596D01*
X101635Y-213305D01*
X102946Y-211847D01*
X103819Y-209805D01*
Y-196097D01*
G01Y-198430D02*
X102946Y-197263D01*
X101635Y-196388D01*
X100107Y-196097D01*
X98361Y-196680D01*
X97269Y-197846D01*
X96395Y-199888D01*
X95959Y-201930D01*
X96177Y-203680D01*
X97051Y-205722D01*
X98361Y-207180D01*
X100107Y-207763D01*
X101417Y-207471D01*
X102946Y-206305D01*
X103819Y-205139D01*
G01X113677Y-207763D02*
Y-196097D01*
G01Y-199013D02*
X114551Y-197555D01*
X115861Y-196388D01*
X117607Y-196097D01*
X119135Y-196388D01*
X120446Y-197555D01*
X121101Y-199596D01*
Y-207763D01*
G01X131614Y-199888D02*
X138601D01*
X137946Y-197846D01*
X136854Y-196680D01*
X135326Y-196097D01*
X133797Y-196388D01*
X132487Y-197263D01*
X131614Y-199305D01*
X131177Y-201055D01*
Y-202805D01*
X131614Y-204555D01*
X132706Y-206305D01*
X134016Y-207471D01*
X135544Y-207763D01*
X137072Y-207180D01*
X138601Y-205430D01*
G01X149332Y-207763D02*
Y-196097D01*
G01Y-198430D02*
X150424Y-197263D01*
X151516Y-196388D01*
X153044Y-196097D01*
X154135Y-196388D01*
X155446Y-197263D01*
G01X196089Y-252763D02*
Y-235263D01*
X193469Y-238763D01*
G01Y-252763D02*
X198709D01*
G01X213589Y-235263D02*
X211842Y-235846D01*
X210532Y-237305D01*
X209659Y-239054D01*
X209004Y-241388D01*
X208786Y-244013D01*
X209004Y-246638D01*
X209659Y-248972D01*
X210532Y-250722D01*
X211842Y-252180D01*
X213589Y-252763D01*
X215335Y-252180D01*
X216646Y-250722D01*
X217519Y-248972D01*
X218174Y-246638D01*
X218392Y-244013D01*
X218174Y-241388D01*
X217519Y-239054D01*
X216646Y-237305D01*
X215335Y-235846D01*
X213589Y-235263D01*
G01X227159Y-253346D02*
X235019Y-235263D01*
G01X248589Y-252763D02*
Y-235263D01*
X245969Y-238763D01*
G01Y-252763D02*
X251209D01*
G01X261941Y-245472D02*
X263469Y-243430D01*
X264779Y-242263D01*
X266526Y-241680D01*
X268054Y-242263D01*
X269146Y-243430D01*
X270019Y-245180D01*
X270237Y-247221D01*
X270019Y-248972D01*
X269146Y-250722D01*
X267835Y-252180D01*
X266307Y-252763D01*
X264561Y-252180D01*
X263032Y-250430D01*
X262159Y-247805D01*
X261941Y-244888D01*
X262377Y-241097D01*
X263032Y-239054D01*
X264124Y-237013D01*
X265652Y-235555D01*
X267181Y-235263D01*
X268709Y-235846D01*
X269801Y-237305D01*
G01X279659Y-253346D02*
X287519Y-235263D01*
G01X296941Y-238180D02*
X298251Y-236430D01*
X299779Y-235555D01*
X301526Y-235263D01*
X303709Y-235846D01*
X305237Y-237305D01*
X305674Y-239054D01*
X305456Y-240805D01*
X304582Y-242263D01*
X300216Y-245180D01*
X298251Y-247221D01*
X296941Y-250139D01*
X296504Y-252763D01*
X305674D01*
G01X318589Y-235263D02*
X316842Y-235846D01*
X315532Y-237305D01*
X314659Y-239054D01*
X314004Y-241388D01*
X313786Y-244013D01*
X314004Y-246638D01*
X314659Y-248972D01*
X315532Y-250722D01*
X316842Y-252180D01*
X318589Y-252763D01*
X320335Y-252180D01*
X321646Y-250722D01*
X322519Y-248972D01*
X323174Y-246638D01*
X323392Y-244013D01*
X323174Y-241388D01*
X322519Y-239054D01*
X321646Y-237305D01*
X320335Y-235846D01*
X318589Y-235263D01*
G01X336089Y-252763D02*
Y-235263D01*
X333469Y-238763D01*
G01Y-252763D02*
X338709D01*
G01X349441Y-238180D02*
X350751Y-236430D01*
X352279Y-235555D01*
X354026Y-235263D01*
X356209Y-235846D01*
X357737Y-237305D01*
X358174Y-239054D01*
X357956Y-240805D01*
X357082Y-242263D01*
X352716Y-245180D01*
X350751Y-247221D01*
X349441Y-250139D01*
X349004Y-252763D01*
X358174D01*
G01X243786Y-207763D02*
Y-190263D01*
X248152D01*
X249899Y-191138D01*
X251209Y-192305D01*
X252301Y-194054D01*
X253174Y-196097D01*
X253392Y-199013D01*
X253174Y-201930D01*
X252301Y-203972D01*
X251209Y-205722D01*
X249899Y-206888D01*
X248152Y-207763D01*
X243786D01*
G01X270019D02*
Y-196097D01*
G01Y-198138D02*
X269146Y-196972D01*
X267835Y-196388D01*
X266307Y-196097D01*
X264779Y-196680D01*
X263469Y-197846D01*
X262595Y-199596D01*
X262159Y-201930D01*
X262595Y-204263D01*
X263469Y-206013D01*
X264779Y-207180D01*
X266307Y-207763D01*
X267835Y-207471D01*
X269146Y-206597D01*
X270019Y-205430D01*
G01X283589Y-190263D02*
Y-207763D01*
G01X280532Y-196097D02*
X286646D01*
G01X297814Y-199888D02*
X304801D01*
X304146Y-197846D01*
X303054Y-196680D01*
X301526Y-196097D01*
X299997Y-196388D01*
X298687Y-197263D01*
X297814Y-199305D01*
X297377Y-201055D01*
Y-202805D01*
X297814Y-204555D01*
X298906Y-206305D01*
X300216Y-207471D01*
X301744Y-207763D01*
X303272Y-207180D01*
X304801Y-205430D01*
M02*
